(kicad_sch
	(version 20250114)
	(generator "eeschema")
	(generator_version "9.0")
	(paper "A3")
	(title_block
		(title "Thunderbolt to 10GbE adapter")
		(date "2026-04-23")
		(rev "1.1.0")
		(company "Antmicro Ltd")
		(comment 1 "www.antmicro.com")
	)
	(text "[place on bottom]"
		(exclude_from_sim no)
		(at 388.62 212.09 0)
		(effects
			(font
				(size 1.27 1.27)
			)
		)
	)
	(text "1V DC-DC"
		(exclude_from_sim no)
		(at 172.72 132.08 0)
		(effects
			(font
				(size 2.54 2.54)
				(thickness 0.508)
				(bold yes)
			)
		)
	)
	(text "3V3"
		(exclude_from_sim no)
		(at 210.566 19.558 0)
		(effects
			(font
				(size 1.27 1.27)
			)
		)
	)
	(text "5V internal LDO"
		(exclude_from_sim no)
		(at 271.272 143.764 0)
		(effects
			(font
				(size 1.27 1.27)
			)
		)
	)
	(text "-->"
		(exclude_from_sim no)
		(at 246.634 19.304 0)
		(effects
			(font
				(size 1.27 1.27)
			)
		)
	)
	(text "DVDD (1V0)"
		(exclude_from_sim no)
		(at 265.938 19.558 0)
		(effects
			(font
				(size 1.27 1.27)
			)
		)
	)
	(text "max 100ms"
		(exclude_from_sim no)
		(at 215.646 18.288 0)
		(effects
			(font
				(size 0.635 0.635)
			)
		)
	)
	(text "3V3 DC-DC"
		(exclude_from_sim no)
		(at 172.72 17.78 0)
		(effects
			(font
				(size 2.54 2.54)
				(thickness 0.508)
				(bold yes)
			)
		)
	)
	(text "1V88 DC-DC"
		(exclude_from_sim no)
		(at 172.72 93.98 0)
		(effects
			(font
				(size 2.54 2.54)
				(thickness 0.508)
				(bold yes)
			)
		)
	)
	(text "5V internal LDO"
		(exclude_from_sim no)
		(at 271.272 181.864 0)
		(effects
			(font
				(size 1.27 1.27)
			)
		)
	)
	(text "PGOOD LED"
		(exclude_from_sim no)
		(at 295.656 226.314 0)
		(effects
			(font
				(size 1.27 1.27)
			)
		)
	)
	(text "1V88"
		(exclude_from_sim no)
		(at 241.046 19.558 0)
		(effects
			(font
				(size 1.27 1.27)
			)
		)
	)
	(text "UVLO\n3V3 rail is first in \nthe power sequence,\nso deasserting its\nenable pin \nturns off remainng \nDC-DC converters"
		(exclude_from_sim no)
		(at 179.07 39.37 0)
		(effects
			(font
				(size 1.27 1.27)
			)
		)
	)
	(text "-->"
		(exclude_from_sim no)
		(at 215.646 19.304 0)
		(effects
			(font
				(size 1.27 1.27)
			)
		)
	)
	(text "1V0"
		(exclude_from_sim no)
		(at 252.476 19.558 0)
		(effects
			(font
				(size 1.27 1.27)
			)
		)
	)
	(text "VCCD (0.92V)"
		(exclude_from_sim no)
		(at 225.806 19.558 0)
		(effects
			(font
				(size 1.27 1.27)
			)
		)
	)
	(text "5V internal LDO"
		(exclude_from_sim no)
		(at 271.272 67.564 0)
		(effects
			(font
				(size 1.27 1.27)
			)
		)
	)
	(text "V_{OUT} = 0.6 x (1 + R_{H}/R_{L}) [V]"
		(exclude_from_sim no)
		(at 160.02 200.66 0)
		(effects
			(font
				(size 1.27 1.27)
			)
			(justify left)
		)
	)
	(text "-->"
		(exclude_from_sim no)
		(at 257.556 19.304 0)
		(effects
			(font
				(size 1.27 1.27)
			)
		)
	)
	(text "5V internal LDO"
		(exclude_from_sim no)
		(at 271.272 29.464 0)
		(effects
			(font
				(size 1.27 1.27)
			)
		)
	)
	(text "0V92 DC-DC"
		(exclude_from_sim no)
		(at 172.72 55.88 0)
		(effects
			(font
				(size 2.54 2.54)
				(thickness 0.508)
				(bold yes)
			)
		)
	)
	(text "-->"
		(exclude_from_sim no)
		(at 235.204 19.304 0)
		(effects
			(font
				(size 1.27 1.27)
			)
		)
	)
	(text "DVDD DC-DC"
		(exclude_from_sim no)
		(at 172.72 170.18 0)
		(effects
			(font
				(size 2.54 2.54)
				(thickness 0.508)
				(bold yes)
			)
		)
	)
	(text "ICT Testpoints"
		(exclude_from_sim no)
		(at 388.62 208.28 0)
		(effects
			(font
				(size 2.54 2.54)
				(thickness 0.508)
				(bold yes)
			)
		)
	)
	(text "5V internal LDO"
		(exclude_from_sim no)
		(at 271.272 105.664 0)
		(effects
			(font
				(size 1.27 1.27)
			)
		)
	)
	(text_box "0.87-0.96V\nMax ripple: 20mV_{p-p}"
		(exclude_from_sim no)
		(at 161.036 59.182 0)
		(size 22.86 6.35)
		(margins 0.9525 0.9525 0.9525 0.9525)
		(stroke
			(width 0)
			(type solid)
		)
		(fill
			(type none)
		)
		(effects
			(font
				(size 1.27 1.27)
			)
		)
	)
	(text_box "0.95-1.05V\nMax ripple: 10mV_{p-p}"
		(exclude_from_sim no)
		(at 161.036 135.382 0)
		(size 22.86 6.35)
		(margins 0.9525 0.9525 0.9525 0.9525)
		(stroke
			(width 0)
			(type solid)
		)
		(fill
			(type none)
		)
		(effects
			(font
				(size 1.27 1.27)
			)
		)
	)
	(text_box "1.8236-1.9364V\nMax ripple: 50mV_{p-p}"
		(exclude_from_sim no)
		(at 161.036 97.282 0)
		(size 22.86 6.35)
		(margins 0.9525 0.9525 0.9525 0.9525)
		(stroke
			(width 0)
			(type solid)
		)
		(fill
			(type none)
		)
		(effects
			(font
				(size 1.27 1.27)
			)
		)
	)
	(text_box "0.95-1.05V\nMax ripple: 30mV_{p-p}"
		(exclude_from_sim no)
		(at 161.036 173.482 0)
		(size 22.86 6.35)
		(margins 0.9525 0.9525 0.9525 0.9525)
		(stroke
			(width 0)
			(type solid)
		)
		(fill
			(type none)
		)
		(effects
			(font
				(size 1.27 1.27)
			)
		)
	)
	(text_box "3.14-3.47V\nMax ripple: 70mV_{p-p}"
		(exclude_from_sim no)
		(at 161.036 21.082 0)
		(size 22.86 6.35)
		(margins 0.9525 0.9525 0.9525 0.9525)
		(stroke
			(width 0)
			(type solid)
		)
		(fill
			(type none)
		)
		(effects
			(font
				(size 1.27 1.27)
			)
		)
	)
	(junction
		(at 391.16 25.4)
		(diameter 0)
		(color 0 0 0 0)
	)
	(junction
		(at 307.34 25.4)
		(diameter 0)
		(color 0 0 0 0)
	)
	(junction
		(at 332.74 101.6)
		(diameter 0)
		(color 0 0 0 0)
	)
	(junction
		(at 391.16 63.5)
		(diameter 0)
		(color 0 0 0 0)
	)
	(junction
		(at 327.66 149.86)
		(diameter 0)
		(color 0 0 0 0)
	)
	(junction
		(at 217.17 177.8)
		(diameter 0)
		(color 0 0 0 0)
	)
	(junction
		(at 332.74 25.4)
		(diameter 0)
		(color 0 0 0 0)
	)
	(junction
		(at 259.08 78.74)
		(diameter 0)
		(color 0 0 0 0)
	)
	(junction
		(at 279.4 215.9)
		(diameter 0)
		(color 0 0 0 0)
	)
	(junction
		(at 237.49 177.8)
		(diameter 0)
		(color 0 0 0 0)
	)
	(junction
		(at 354.33 25.4)
		(diameter 0)
		(color 0 0 0 0)
	)
	(junction
		(at 344.17 177.8)
		(diameter 0)
		(color 0 0 0 0)
	)
	(junction
		(at 254 215.9)
		(diameter 0)
		(color 0 0 0 0)
	)
	(junction
		(at 217.17 101.6)
		(diameter 0)
		(color 0 0 0 0)
	)
	(junction
		(at 259.08 116.84)
		(diameter 0)
		(color 0 0 0 0)
	)
	(junction
		(at 354.33 177.8)
		(diameter 0)
		(color 0 0 0 0)
	)
	(junction
		(at 217.17 139.7)
		(diameter 0)
		(color 0 0 0 0)
	)
	(junction
		(at 327.66 139.7)
		(diameter 0)
		(color 0 0 0 0)
	)
	(junction
		(at 327.66 25.4)
		(diameter 0)
		(color 0 0 0 0)
	)
	(junction
		(at 332.74 73.66)
		(diameter 0)
		(color 0 0 0 0)
	)
	(junction
		(at 391.16 139.7)
		(diameter 0)
		(color 0 0 0 0)
	)
	(junction
		(at 256.54 66.04)
		(diameter 0)
		(color 0 0 0 0)
	)
	(junction
		(at 327.66 177.8)
		(diameter 0)
		(color 0 0 0 0)
	)
	(junction
		(at 354.33 139.7)
		(diameter 0)
		(color 0 0 0 0)
	)
	(junction
		(at 237.49 101.6)
		(diameter 0)
		(color 0 0 0 0)
	)
	(junction
		(at 307.34 177.8)
		(diameter 0)
		(color 0 0 0 0)
	)
	(junction
		(at 237.49 25.4)
		(diameter 0)
		(color 0 0 0 0)
	)
	(junction
		(at 177.8 215.9)
		(diameter 0)
		(color 0 0 0 0)
	)
	(junction
		(at 227.33 25.4)
		(diameter 0)
		(color 0 0 0 0)
	)
	(junction
		(at 227.33 63.5)
		(diameter 0)
		(color 0 0 0 0)
	)
	(junction
		(at 332.74 111.76)
		(diameter 0)
		(color 0 0 0 0)
	)
	(junction
		(at 332.74 35.56)
		(diameter 0)
		(color 0 0 0 0)
	)
	(junction
		(at 237.49 139.7)
		(diameter 0)
		(color 0 0 0 0)
	)
	(junction
		(at 374.65 177.8)
		(diameter 0)
		(color 0 0 0 0)
	)
	(junction
		(at 391.16 177.8)
		(diameter 0)
		(color 0 0 0 0)
	)
	(junction
		(at 364.49 63.5)
		(diameter 0)
		(color 0 0 0 0)
	)
	(junction
		(at 217.17 25.4)
		(diameter 0)
		(color 0 0 0 0)
	)
	(junction
		(at 256.54 104.14)
		(diameter 0)
		(color 0 0 0 0)
	)
	(junction
		(at 374.65 139.7)
		(diameter 0)
		(color 0 0 0 0)
	)
	(junction
		(at 344.17 63.5)
		(diameter 0)
		(color 0 0 0 0)
	)
	(junction
		(at 364.49 177.8)
		(diameter 0)
		(color 0 0 0 0)
	)
	(junction
		(at 256.54 27.94)
		(diameter 0)
		(color 0 0 0 0)
	)
	(junction
		(at 354.33 63.5)
		(diameter 0)
		(color 0 0 0 0)
	)
	(junction
		(at 332.74 63.5)
		(diameter 0)
		(color 0 0 0 0)
	)
	(junction
		(at 256.54 180.34)
		(diameter 0)
		(color 0 0 0 0)
	)
	(junction
		(at 374.65 101.6)
		(diameter 0)
		(color 0 0 0 0)
	)
	(junction
		(at 344.17 25.4)
		(diameter 0)
		(color 0 0 0 0)
	)
	(junction
		(at 307.34 101.6)
		(diameter 0)
		(color 0 0 0 0)
	)
	(junction
		(at 228.6 215.9)
		(diameter 0)
		(color 0 0 0 0)
	)
	(junction
		(at 374.65 63.5)
		(diameter 0)
		(color 0 0 0 0)
	)
	(junction
		(at 227.33 177.8)
		(diameter 0)
		(color 0 0 0 0)
	)
	(junction
		(at 327.66 63.5)
		(diameter 0)
		(color 0 0 0 0)
	)
	(junction
		(at 332.74 149.86)
		(diameter 0)
		(color 0 0 0 0)
	)
	(junction
		(at 354.33 101.6)
		(diameter 0)
		(color 0 0 0 0)
	)
	(junction
		(at 203.2 215.9)
		(diameter 0)
		(color 0 0 0 0)
	)
	(junction
		(at 256.54 142.24)
		(diameter 0)
		(color 0 0 0 0)
	)
	(junction
		(at 344.17 139.7)
		(diameter 0)
		(color 0 0 0 0)
	)
	(junction
		(at 364.49 101.6)
		(diameter 0)
		(color 0 0 0 0)
	)
	(junction
		(at 237.49 63.5)
		(diameter 0)
		(color 0 0 0 0)
	)
	(junction
		(at 256.54 193.04)
		(diameter 0)
		(color 0 0 0 0)
	)
	(junction
		(at 327.66 73.66)
		(diameter 0)
		(color 0 0 0 0)
	)
	(junction
		(at 364.49 25.4)
		(diameter 0)
		(color 0 0 0 0)
	)
	(junction
		(at 259.08 40.64)
		(diameter 0)
		(color 0 0 0 0)
	)
	(junction
		(at 227.33 101.6)
		(diameter 0)
		(color 0 0 0 0)
	)
	(junction
		(at 364.49 139.7)
		(diameter 0)
		(color 0 0 0 0)
	)
	(junction
		(at 327.66 35.56)
		(diameter 0)
		(color 0 0 0 0)
	)
	(junction
		(at 307.34 139.7)
		(diameter 0)
		(color 0 0 0 0)
	)
	(junction
		(at 391.16 101.6)
		(diameter 0)
		(color 0 0 0 0)
	)
	(junction
		(at 217.17 63.5)
		(diameter 0)
		(color 0 0 0 0)
	)
	(junction
		(at 344.17 101.6)
		(diameter 0)
		(color 0 0 0 0)
	)
	(junction
		(at 332.74 139.7)
		(diameter 0)
		(color 0 0 0 0)
	)
	(junction
		(at 307.34 63.5)
		(diameter 0)
		(color 0 0 0 0)
	)
	(junction
		(at 227.33 139.7)
		(diameter 0)
		(color 0 0 0 0)
	)
	(junction
		(at 327.66 111.76)
		(diameter 0)
		(color 0 0 0 0)
	)
	(junction
		(at 332.74 177.8)
		(diameter 0)
		(color 0 0 0 0)
	)
	(junction
		(at 259.08 154.94)
		(diameter 0)
		(color 0 0 0 0)
	)
	(junction
		(at 327.66 187.96)
		(diameter 0)
		(color 0 0 0 0)
	)
	(junction
		(at 327.66 101.6)
		(diameter 0)
		(color 0 0 0 0)
	)
	(junction
		(at 332.74 187.96)
		(diameter 0)
		(color 0 0 0 0)
	)
	(junction
		(at 374.65 25.4)
		(diameter 0)
		(color 0 0 0 0)
	)
	(wire
		(pts
			(xy 327.66 101.6) (xy 327.66 104.14)
		)
		(stroke
			(width 0)
			(type default)
		)
	)
	(wire
		(pts
			(xy 256.54 205.74) (xy 256.54 193.04)
		)
		(stroke
			(width 0)
			(type default)
		)
	)
	(wire
		(pts
			(xy 344.17 195.58) (xy 344.17 190.5)
		)
		(stroke
			(width 0)
			(type default)
		)
	)
	(wire
		(pts
			(xy 384.81 101.6) (xy 391.16 101.6)
		)
		(stroke
			(width 0)
			(type default)
		)
	)
	(wire
		(pts
			(xy 320.04 177.8) (xy 327.66 177.8)
		)
		(stroke
			(width 0)
			(type default)
		)
	)
	(wire
		(pts
			(xy 256.54 152.4) (xy 256.54 154.94)
		)
		(stroke
			(width 0)
			(type default)
		)
	)
	(wire
		(pts
			(xy 227.33 139.7) (xy 237.49 139.7)
		)
		(stroke
			(width 0)
			(type default)
		)
	)
	(wire
		(pts
			(xy 354.33 63.5) (xy 364.49 63.5)
		)
		(stroke
			(width 0)
			(type default)
		)
	)
	(polyline
		(pts
			(xy 157.48 127) (xy 407.67 127)
		)
		(stroke
			(width 0)
			(type dash)
		)
	)
	(wire
		(pts
			(xy 254 215.9) (xy 254 218.44)
		)
		(stroke
			(width 0)
			(type default)
		)
	)
	(wire
		(pts
			(xy 237.49 139.7) (xy 276.86 139.7)
		)
		(stroke
			(width 0)
			(type default)
		)
	)
	(wire
		(pts
			(xy 294.64 106.68) (xy 307.34 106.68)
		)
		(stroke
			(width 0)
			(type default)
		)
	)
	(polyline
		(pts
			(xy 157.48 88.9) (xy 407.67 88.9)
		)
		(stroke
			(width 0)
			(type dash)
		)
	)
	(wire
		(pts
			(xy 203.2 215.9) (xy 203.2 218.44)
		)
		(stroke
			(width 0)
			(type default)
		)
	)
	(wire
		(pts
			(xy 166.37 215.9) (xy 177.8 215.9)
		)
		(stroke
			(width 0)
			(type default)
		)
	)
	(wire
		(pts
			(xy 217.17 101.6) (xy 227.33 101.6)
		)
		(stroke
			(width 0)
			(type default)
		)
	)
	(wire
		(pts
			(xy 203.2 223.52) (xy 203.2 226.06)
		)
		(stroke
			(width 0)
			(type default)
		)
	)
	(wire
		(pts
			(xy 327.66 177.8) (xy 327.66 180.34)
		)
		(stroke
			(width 0)
			(type default)
		)
	)
	(wire
		(pts
			(xy 400.05 101.6) (xy 400.05 99.06)
		)
		(stroke
			(width 0)
			(type default)
		)
	)
	(wire
		(pts
			(xy 304.8 231.14) (xy 304.8 228.6)
		)
		(stroke
			(width 0)
			(type default)
		)
	)
	(wire
		(pts
			(xy 228.6 215.9) (xy 254 215.9)
		)
		(stroke
			(width 0)
			(type default)
		)
	)
	(wire
		(pts
			(xy 227.33 139.7) (xy 227.33 147.32)
		)
		(stroke
			(width 0)
			(type default)
		)
	)
	(wire
		(pts
			(xy 256.54 180.34) (xy 276.86 180.34)
		)
		(stroke
			(width 0)
			(type default)
		)
	)
	(wire
		(pts
			(xy 279.4 233.68) (xy 279.4 231.14)
		)
		(stroke
			(width 0)
			(type default)
		)
	)
	(wire
		(pts
			(xy 332.74 147.32) (xy 332.74 149.86)
		)
		(stroke
			(width 0)
			(type default)
		)
	)
	(wire
		(pts
			(xy 344.17 63.5) (xy 354.33 63.5)
		)
		(stroke
			(width 0)
			(type default)
		)
	)
	(wire
		(pts
			(xy 344.17 139.7) (xy 344.17 147.32)
		)
		(stroke
			(width 0)
			(type default)
		)
	)
	(wire
		(pts
			(xy 294.64 182.88) (xy 307.34 182.88)
		)
		(stroke
			(width 0)
			(type default)
		)
	)
	(wire
		(pts
			(xy 259.08 154.94) (xy 276.86 154.94)
		)
		(stroke
			(width 0)
			(type default)
		)
	)
	(wire
		(pts
			(xy 227.33 157.48) (xy 227.33 152.4)
		)
		(stroke
			(width 0)
			(type default)
		)
	)
	(wire
		(pts
			(xy 374.65 177.8) (xy 374.65 185.42)
		)
		(stroke
			(width 0)
			(type default)
		)
	)
	(wire
		(pts
			(xy 247.65 66.04) (xy 256.54 66.04)
		)
		(stroke
			(width 0)
			(type default)
		)
	)
	(wire
		(pts
			(xy 332.74 177.8) (xy 332.74 180.34)
		)
		(stroke
			(width 0)
			(type default)
		)
	)
	(wire
		(pts
			(xy 259.08 111.76) (xy 261.62 111.76)
		)
		(stroke
			(width 0)
			(type default)
		)
	)
	(wire
		(pts
			(xy 297.18 119.38) (xy 297.18 116.84)
		)
		(stroke
			(width 0)
			(type default)
		)
	)
	(wire
		(pts
			(xy 237.49 119.38) (xy 237.49 114.3)
		)
		(stroke
			(width 0)
			(type default)
		)
	)
	(wire
		(pts
			(xy 344.17 25.4) (xy 344.17 33.02)
		)
		(stroke
			(width 0)
			(type default)
		)
	)
	(wire
		(pts
			(xy 391.16 139.7) (xy 400.05 139.7)
		)
		(stroke
			(width 0)
			(type default)
		)
	)
	(wire
		(pts
			(xy 332.74 177.8) (xy 327.66 177.8)
		)
		(stroke
			(width 0)
			(type default)
		)
	)
	(polyline
		(pts
			(xy 157.48 203.2) (xy 407.67 203.2)
		)
		(stroke
			(width 0)
			(type dash)
		)
	)
	(wire
		(pts
			(xy 391.16 25.4) (xy 400.05 25.4)
		)
		(stroke
			(width 0)
			(type default)
		)
	)
	(wire
		(pts
			(xy 327.66 109.22) (xy 327.66 111.76)
		)
		(stroke
			(width 0)
			(type default)
		)
	)
	(wire
		(pts
			(xy 266.7 111.76) (xy 276.86 111.76)
		)
		(stroke
			(width 0)
			(type default)
		)
	)
	(wire
		(pts
			(xy 364.49 177.8) (xy 364.49 185.42)
		)
		(stroke
			(width 0)
			(type default)
		)
	)
	(wire
		(pts
			(xy 391.16 99.06) (xy 391.16 101.6)
		)
		(stroke
			(width 0)
			(type default)
		)
	)
	(wire
		(pts
			(xy 217.17 177.8) (xy 217.17 185.42)
		)
		(stroke
			(width 0)
			(type default)
		)
	)
	(wire
		(pts
			(xy 259.08 40.64) (xy 256.54 40.64)
		)
		(stroke
			(width 0)
			(type default)
		)
	)
	(wire
		(pts
			(xy 256.54 114.3) (xy 256.54 116.84)
		)
		(stroke
			(width 0)
			(type default)
		)
	)
	(wire
		(pts
			(xy 354.33 81.28) (xy 354.33 76.2)
		)
		(stroke
			(width 0)
			(type default)
		)
	)
	(wire
		(pts
			(xy 297.18 154.94) (xy 294.64 154.94)
		)
		(stroke
			(width 0)
			(type default)
		)
	)
	(wire
		(pts
			(xy 384.81 139.7) (xy 391.16 139.7)
		)
		(stroke
			(width 0)
			(type default)
		)
	)
	(wire
		(pts
			(xy 374.65 101.6) (xy 374.65 109.22)
		)
		(stroke
			(width 0)
			(type default)
		)
	)
	(wire
		(pts
			(xy 354.33 101.6) (xy 364.49 101.6)
		)
		(stroke
			(width 0)
			(type default)
		)
	)
	(wire
		(pts
			(xy 391.16 231.14) (xy 387.35 231.14)
		)
		(stroke
			(width 0)
			(type default)
		)
	)
	(wire
		(pts
			(xy 332.74 25.4) (xy 327.66 25.4)
		)
		(stroke
			(width 0)
			(type default)
		)
	)
	(wire
		(pts
			(xy 320.04 63.5) (xy 327.66 63.5)
		)
		(stroke
			(width 0)
			(type default)
		)
	)
	(wire
		(pts
			(xy 227.33 177.8) (xy 227.33 185.42)
		)
		(stroke
			(width 0)
			(type default)
		)
	)
	(wire
		(pts
			(xy 227.33 119.38) (xy 227.33 114.3)
		)
		(stroke
			(width 0)
			(type default)
		)
	)
	(wire
		(pts
			(xy 227.33 63.5) (xy 227.33 71.12)
		)
		(stroke
			(width 0)
			(type default)
		)
	)
	(wire
		(pts
			(xy 327.66 139.7) (xy 327.66 142.24)
		)
		(stroke
			(width 0)
			(type default)
		)
	)
	(wire
		(pts
			(xy 400.05 63.5) (xy 400.05 60.96)
		)
		(stroke
			(width 0)
			(type default)
		)
	)
	(wire
		(pts
			(xy 320.04 25.4) (xy 327.66 25.4)
		)
		(stroke
			(width 0)
			(type default)
		)
	)
	(wire
		(pts
			(xy 294.64 68.58) (xy 307.34 68.58)
		)
		(stroke
			(width 0)
			(type default)
		)
	)
	(wire
		(pts
			(xy 247.65 81.28) (xy 247.65 76.2)
		)
		(stroke
			(width 0)
			(type default)
		)
	)
	(wire
		(pts
			(xy 332.74 71.12) (xy 332.74 73.66)
		)
		(stroke
			(width 0)
			(type default)
		)
	)
	(wire
		(pts
			(xy 279.4 223.52) (xy 279.4 226.06)
		)
		(stroke
			(width 0)
			(type default)
		)
	)
	(wire
		(pts
			(xy 256.54 193.04) (xy 276.86 193.04)
		)
		(stroke
			(width 0)
			(type default)
		)
	)
	(wire
		(pts
			(xy 327.66 73.66) (xy 332.74 73.66)
		)
		(stroke
			(width 0)
			(type default)
		)
	)
	(wire
		(pts
			(xy 364.49 177.8) (xy 374.65 177.8)
		)
		(stroke
			(width 0)
			(type default)
		)
	)
	(wire
		(pts
			(xy 256.54 27.94) (xy 276.86 27.94)
		)
		(stroke
			(width 0)
			(type default)
		)
	)
	(wire
		(pts
			(xy 332.74 25.4) (xy 344.17 25.4)
		)
		(stroke
			(width 0)
			(type default)
		)
	)
	(wire
		(pts
			(xy 332.74 187.96) (xy 332.74 189.23)
		)
		(stroke
			(width 0)
			(type default)
		)
	)
	(wire
		(pts
			(xy 266.7 187.96) (xy 276.86 187.96)
		)
		(stroke
			(width 0)
			(type default)
		)
	)
	(wire
		(pts
			(xy 374.65 119.38) (xy 374.65 114.3)
		)
		(stroke
			(width 0)
			(type default)
		)
	)
	(wire
		(pts
			(xy 177.8 215.9) (xy 203.2 215.9)
		)
		(stroke
			(width 0)
			(type default)
		)
	)
	(wire
		(pts
			(xy 227.33 177.8) (xy 237.49 177.8)
		)
		(stroke
			(width 0)
			(type default)
		)
	)
	(wire
		(pts
			(xy 332.74 41.91) (xy 332.74 43.18)
		)
		(stroke
			(width 0)
			(type default)
		)
	)
	(wire
		(pts
			(xy 256.54 104.14) (xy 276.86 104.14)
		)
		(stroke
			(width 0)
			(type default)
		)
	)
	(wire
		(pts
			(xy 327.66 185.42) (xy 327.66 187.96)
		)
		(stroke
			(width 0)
			(type default)
		)
	)
	(wire
		(pts
			(xy 259.08 73.66) (xy 261.62 73.66)
		)
		(stroke
			(width 0)
			(type default)
		)
	)
	(wire
		(pts
			(xy 237.49 81.28) (xy 237.49 76.2)
		)
		(stroke
			(width 0)
			(type default)
		)
	)
	(wire
		(pts
			(xy 332.74 25.4) (xy 332.74 27.94)
		)
		(stroke
			(width 0)
			(type default)
		)
	)
	(wire
		(pts
			(xy 364.49 119.38) (xy 364.49 114.3)
		)
		(stroke
			(width 0)
			(type default)
		)
	)
	(wire
		(pts
			(xy 217.17 137.16) (xy 217.17 139.7)
		)
		(stroke
			(width 0)
			(type default)
		)
	)
	(wire
		(pts
			(xy 354.33 63.5) (xy 354.33 71.12)
		)
		(stroke
			(width 0)
			(type default)
		)
	)
	(wire
		(pts
			(xy 247.65 27.94) (xy 256.54 27.94)
		)
		(stroke
			(width 0)
			(type default)
		)
	)
	(wire
		(pts
			(xy 259.08 40.64) (xy 276.86 40.64)
		)
		(stroke
			(width 0)
			(type default)
		)
	)
	(wire
		(pts
			(xy 344.17 63.5) (xy 344.17 71.12)
		)
		(stroke
			(width 0)
			(type default)
		)
	)
	(wire
		(pts
			(xy 256.54 142.24) (xy 276.86 142.24)
		)
		(stroke
			(width 0)
			(type default)
		)
	)
	(wire
		(pts
			(xy 297.18 193.04) (xy 294.64 193.04)
		)
		(stroke
			(width 0)
			(type default)
		)
	)
	(wire
		(pts
			(xy 391.16 238.76) (xy 387.35 238.76)
		)
		(stroke
			(width 0)
			(type default)
		)
	)
	(wire
		(pts
			(xy 374.65 63.5) (xy 374.65 71.12)
		)
		(stroke
			(width 0)
			(type default)
		)
	)
	(wire
		(pts
			(xy 294.64 73.66) (xy 327.66 73.66)
		)
		(stroke
			(width 0)
			(type default)
		)
	)
	(wire
		(pts
			(xy 332.74 118.11) (xy 332.74 119.38)
		)
		(stroke
			(width 0)
			(type default)
		)
	)
	(wire
		(pts
			(xy 332.74 33.02) (xy 332.74 35.56)
		)
		(stroke
			(width 0)
			(type default)
		)
	)
	(wire
		(pts
			(xy 332.74 111.76) (xy 332.74 113.03)
		)
		(stroke
			(width 0)
			(type default)
		)
	)
	(wire
		(pts
			(xy 320.04 139.7) (xy 327.66 139.7)
		)
		(stroke
			(width 0)
			(type default)
		)
	)
	(polyline
		(pts
			(xy 157.48 165.1) (xy 407.67 165.1)
		)
		(stroke
			(width 0)
			(type dash)
		)
	)
	(wire
		(pts
			(xy 254 243.84) (xy 254 246.38)
		)
		(stroke
			(width 0)
			(type default)
		)
	)
	(wire
		(pts
			(xy 228.6 243.84) (xy 228.6 246.38)
		)
		(stroke
			(width 0)
			(type default)
		)
	)
	(wire
		(pts
			(xy 314.96 139.7) (xy 307.34 139.7)
		)
		(stroke
			(width 0)
			(type default)
		)
	)
	(wire
		(pts
			(xy 332.74 35.56) (xy 332.74 36.83)
		)
		(stroke
			(width 0)
			(type default)
		)
	)
	(wire
		(pts
			(xy 388.62 242.57) (xy 388.62 241.3)
		)
		(stroke
			(width 0)
			(type default)
		)
	)
	(wire
		(pts
			(xy 364.49 81.28) (xy 364.49 76.2)
		)
		(stroke
			(width 0)
			(type default)
		)
	)
	(wire
		(pts
			(xy 254 223.52) (xy 254 226.06)
		)
		(stroke
			(width 0)
			(type default)
		)
	)
	(wire
		(pts
			(xy 400.05 22.86) (xy 400.05 25.4)
		)
		(stroke
			(width 0)
			(type default)
		)
	)
	(wire
		(pts
			(xy 294.64 101.6) (xy 307.34 101.6)
		)
		(stroke
			(width 0)
			(type default)
		)
	)
	(wire
		(pts
			(xy 237.49 63.5) (xy 276.86 63.5)
		)
		(stroke
			(width 0)
			(type default)
		)
	)
	(wire
		(pts
			(xy 374.65 157.48) (xy 374.65 152.4)
		)
		(stroke
			(width 0)
			(type default)
		)
	)
	(wire
		(pts
			(xy 217.17 195.58) (xy 217.17 190.5)
		)
		(stroke
			(width 0)
			(type default)
		)
	)
	(wire
		(pts
			(xy 332.74 63.5) (xy 332.74 66.04)
		)
		(stroke
			(width 0)
			(type default)
		)
	)
	(wire
		(pts
			(xy 354.33 195.58) (xy 354.33 190.5)
		)
		(stroke
			(width 0)
			(type default)
		)
	)
	(wire
		(pts
			(xy 374.65 63.5) (xy 379.73 63.5)
		)
		(stroke
			(width 0)
			(type default)
		)
	)
	(wire
		(pts
			(xy 294.64 139.7) (xy 307.34 139.7)
		)
		(stroke
			(width 0)
			(type default)
		)
	)
	(wire
		(pts
			(xy 304.8 222.25) (xy 304.8 223.52)
		)
		(stroke
			(width 0)
			(type default)
		)
	)
	(wire
		(pts
			(xy 297.18 78.74) (xy 294.64 78.74)
		)
		(stroke
			(width 0)
			(type default)
		)
	)
	(wire
		(pts
			(xy 391.16 233.68) (xy 387.35 233.68)
		)
		(stroke
			(width 0)
			(type default)
		)
	)
	(wire
		(pts
			(xy 247.65 157.48) (xy 247.65 152.4)
		)
		(stroke
			(width 0)
			(type default)
		)
	)
	(polyline
		(pts
			(xy 368.3 252.73) (xy 368.3 203.2)
		)
		(stroke
			(width 0)
			(type dash)
		)
	)
	(wire
		(pts
			(xy 354.33 101.6) (xy 354.33 109.22)
		)
		(stroke
			(width 0)
			(type default)
		)
	)
	(wire
		(pts
			(xy 259.08 187.96) (xy 261.62 187.96)
		)
		(stroke
			(width 0)
			(type default)
		)
	)
	(wire
		(pts
			(xy 327.66 149.86) (xy 332.74 149.86)
		)
		(stroke
			(width 0)
			(type default)
		)
	)
	(wire
		(pts
			(xy 332.74 63.5) (xy 327.66 63.5)
		)
		(stroke
			(width 0)
			(type default)
		)
	)
	(wire
		(pts
			(xy 327.66 71.12) (xy 327.66 73.66)
		)
		(stroke
			(width 0)
			(type default)
		)
	)
	(polyline
		(pts
			(xy 157.48 50.8) (xy 407.67 50.8)
		)
		(stroke
			(width 0)
			(type dash)
		)
	)
	(wire
		(pts
			(xy 237.49 195.58) (xy 237.49 190.5)
		)
		(stroke
			(width 0)
			(type default)
		)
	)
	(wire
		(pts
			(xy 332.74 149.86) (xy 332.74 151.13)
		)
		(stroke
			(width 0)
			(type default)
		)
	)
	(wire
		(pts
			(xy 354.33 25.4) (xy 354.33 33.02)
		)
		(stroke
			(width 0)
			(type default)
		)
	)
	(wire
		(pts
			(xy 391.16 228.6) (xy 387.35 228.6)
		)
		(stroke
			(width 0)
			(type default)
		)
	)
	(wire
		(pts
			(xy 364.49 101.6) (xy 374.65 101.6)
		)
		(stroke
			(width 0)
			(type default)
		)
	)
	(wire
		(pts
			(xy 177.8 223.52) (xy 177.8 226.06)
		)
		(stroke
			(width 0)
			(type default)
		)
	)
	(polyline
		(pts
			(xy 157.48 284.48) (xy 157.48 12.7)
		)
		(stroke
			(width 0)
			(type dash)
		)
	)
	(wire
		(pts
			(xy 354.33 25.4) (xy 364.49 25.4)
		)
		(stroke
			(width 0)
			(type default)
		)
	)
	(wire
		(pts
			(xy 400.05 139.7) (xy 400.05 137.16)
		)
		(stroke
			(width 0)
			(type default)
		)
	)
	(wire
		(pts
			(xy 297.18 195.58) (xy 297.18 193.04)
		)
		(stroke
			(width 0)
			(type default)
		)
	)
	(wire
		(pts
			(xy 391.16 63.5) (xy 400.05 63.5)
		)
		(stroke
			(width 0)
			(type default)
		)
	)
	(wire
		(pts
			(xy 327.66 33.02) (xy 327.66 35.56)
		)
		(stroke
			(width 0)
			(type default)
		)
	)
	(wire
		(pts
			(xy 259.08 116.84) (xy 276.86 116.84)
		)
		(stroke
			(width 0)
			(type default)
		)
	)
	(wire
		(pts
			(xy 217.17 99.06) (xy 217.17 101.6)
		)
		(stroke
			(width 0)
			(type default)
		)
	)
	(wire
		(pts
			(xy 217.17 139.7) (xy 227.33 139.7)
		)
		(stroke
			(width 0)
			(type default)
		)
	)
	(wire
		(pts
			(xy 344.17 101.6) (xy 344.17 109.22)
		)
		(stroke
			(width 0)
			(type default)
		)
	)
	(wire
		(pts
			(xy 227.33 195.58) (xy 227.33 190.5)
		)
		(stroke
			(width 0)
			(type default)
		)
	)
	(wire
		(pts
			(xy 254 215.9) (xy 279.4 215.9)
		)
		(stroke
			(width 0)
			(type default)
		)
	)
	(wire
		(pts
			(xy 217.17 43.18) (xy 217.17 38.1)
		)
		(stroke
			(width 0)
			(type default)
		)
	)
	(wire
		(pts
			(xy 273.05 35.56) (xy 276.86 35.56)
		)
		(stroke
			(width 0)
			(type default)
		)
	)
	(wire
		(pts
			(xy 354.33 157.48) (xy 354.33 152.4)
		)
		(stroke
			(width 0)
			(type default)
		)
	)
	(wire
		(pts
			(xy 177.8 215.9) (xy 177.8 218.44)
		)
		(stroke
			(width 0)
			(type default)
		)
	)
	(wire
		(pts
			(xy 247.65 142.24) (xy 256.54 142.24)
		)
		(stroke
			(width 0)
			(type default)
		)
	)
	(wire
		(pts
			(xy 234.95 238.76) (xy 246.38 238.76)
		)
		(stroke
			(width 0)
			(type default)
		)
	)
	(wire
		(pts
			(xy 237.49 177.8) (xy 237.49 185.42)
		)
		(stroke
			(width 0)
			(type default)
		)
	)
	(wire
		(pts
			(xy 196.85 22.86) (xy 196.85 25.4)
		)
		(stroke
			(width 0)
			(type default)
		)
	)
	(wire
		(pts
			(xy 314.96 25.4) (xy 307.34 25.4)
		)
		(stroke
			(width 0)
			(type default)
		)
	)
	(wire
		(pts
			(xy 364.49 157.48) (xy 364.49 152.4)
		)
		(stroke
			(width 0)
			(type default)
		)
	)
	(wire
		(pts
			(xy 228.6 223.52) (xy 228.6 226.06)
		)
		(stroke
			(width 0)
			(type default)
		)
	)
	(wire
		(pts
			(xy 374.65 177.8) (xy 379.73 177.8)
		)
		(stroke
			(width 0)
			(type default)
		)
	)
	(wire
		(pts
			(xy 217.17 25.4) (xy 217.17 33.02)
		)
		(stroke
			(width 0)
			(type default)
		)
	)
	(wire
		(pts
			(xy 327.66 147.32) (xy 327.66 149.86)
		)
		(stroke
			(width 0)
			(type default)
		)
	)
	(wire
		(pts
			(xy 256.54 116.84) (xy 259.08 116.84)
		)
		(stroke
			(width 0)
			(type default)
		)
	)
	(wire
		(pts
			(xy 354.33 177.8) (xy 354.33 185.42)
		)
		(stroke
			(width 0)
			(type default)
		)
	)
	(wire
		(pts
			(xy 354.33 139.7) (xy 364.49 139.7)
		)
		(stroke
			(width 0)
			(type default)
		)
	)
	(wire
		(pts
			(xy 344.17 157.48) (xy 344.17 152.4)
		)
		(stroke
			(width 0)
			(type default)
		)
	)
	(wire
		(pts
			(xy 247.65 185.42) (xy 247.65 180.34)
		)
		(stroke
			(width 0)
			(type default)
		)
	)
	(wire
		(pts
			(xy 259.08 78.74) (xy 259.08 111.76)
		)
		(stroke
			(width 0)
			(type default)
		)
	)
	(wire
		(pts
			(xy 196.85 25.4) (xy 217.17 25.4)
		)
		(stroke
			(width 0)
			(type default)
		)
	)
	(wire
		(pts
			(xy 320.04 101.6) (xy 327.66 101.6)
		)
		(stroke
			(width 0)
			(type default)
		)
	)
	(wire
		(pts
			(xy 294.64 30.48) (xy 307.34 30.48)
		)
		(stroke
			(width 0)
			(type default)
		)
	)
	(wire
		(pts
			(xy 259.08 116.84) (xy 259.08 149.86)
		)
		(stroke
			(width 0)
			(type default)
		)
	)
	(wire
		(pts
			(xy 237.49 43.18) (xy 237.49 38.1)
		)
		(stroke
			(width 0)
			(type default)
		)
	)
	(wire
		(pts
			(xy 327.66 111.76) (xy 332.74 111.76)
		)
		(stroke
			(width 0)
			(type default)
		)
	)
	(wire
		(pts
			(xy 332.74 80.01) (xy 332.74 81.28)
		)
		(stroke
			(width 0)
			(type default)
		)
	)
	(wire
		(pts
			(xy 217.17 101.6) (xy 217.17 109.22)
		)
		(stroke
			(width 0)
			(type default)
		)
	)
	(wire
		(pts
			(xy 237.49 157.48) (xy 237.49 152.4)
		)
		(stroke
			(width 0)
			(type default)
		)
	)
	(wire
		(pts
			(xy 344.17 43.18) (xy 344.17 38.1)
		)
		(stroke
			(width 0)
			(type default)
		)
	)
	(wire
		(pts
			(xy 217.17 60.96) (xy 217.17 63.5)
		)
		(stroke
			(width 0)
			(type default)
		)
	)
	(wire
		(pts
			(xy 384.81 177.8) (xy 391.16 177.8)
		)
		(stroke
			(width 0)
			(type default)
		)
	)
	(wire
		(pts
			(xy 247.65 71.12) (xy 247.65 66.04)
		)
		(stroke
			(width 0)
			(type default)
		)
	)
	(wire
		(pts
			(xy 279.4 215.9) (xy 304.8 215.9)
		)
		(stroke
			(width 0)
			(type default)
		)
	)
	(wire
		(pts
			(xy 256.54 66.04) (xy 256.54 71.12)
		)
		(stroke
			(width 0)
			(type default)
		)
	)
	(wire
		(pts
			(xy 344.17 139.7) (xy 354.33 139.7)
		)
		(stroke
			(width 0)
			(type default)
		)
	)
	(wire
		(pts
			(xy 364.49 139.7) (xy 364.49 147.32)
		)
		(stroke
			(width 0)
			(type default)
		)
	)
	(wire
		(pts
			(xy 259.08 78.74) (xy 276.86 78.74)
		)
		(stroke
			(width 0)
			(type default)
		)
	)
	(wire
		(pts
			(xy 256.54 142.24) (xy 256.54 147.32)
		)
		(stroke
			(width 0)
			(type default)
		)
	)
	(wire
		(pts
			(xy 227.33 101.6) (xy 237.49 101.6)
		)
		(stroke
			(width 0)
			(type default)
		)
	)
	(wire
		(pts
			(xy 256.54 190.5) (xy 256.54 193.04)
		)
		(stroke
			(width 0)
			(type default)
		)
	)
	(wire
		(pts
			(xy 256.54 104.14) (xy 256.54 109.22)
		)
		(stroke
			(width 0)
			(type default)
		)
	)
	(wire
		(pts
			(xy 364.49 101.6) (xy 364.49 109.22)
		)
		(stroke
			(width 0)
			(type default)
		)
	)
	(wire
		(pts
			(xy 237.49 25.4) (xy 276.86 25.4)
		)
		(stroke
			(width 0)
			(type default)
		)
	)
	(wire
		(pts
			(xy 294.64 35.56) (xy 327.66 35.56)
		)
		(stroke
			(width 0)
			(type default)
		)
	)
	(wire
		(pts
			(xy 217.17 81.28) (xy 217.17 76.2)
		)
		(stroke
			(width 0)
			(type default)
		)
	)
	(wire
		(pts
			(xy 332.74 194.31) (xy 332.74 195.58)
		)
		(stroke
			(width 0)
			(type default)
		)
	)
	(wire
		(pts
			(xy 227.33 43.18) (xy 227.33 38.1)
		)
		(stroke
			(width 0)
			(type default)
		)
	)
	(wire
		(pts
			(xy 314.96 205.74) (xy 256.54 205.74)
		)
		(stroke
			(width 0)
			(type default)
		)
	)
	(wire
		(pts
			(xy 237.49 101.6) (xy 237.49 109.22)
		)
		(stroke
			(width 0)
			(type default)
		)
	)
	(wire
		(pts
			(xy 332.74 139.7) (xy 332.74 142.24)
		)
		(stroke
			(width 0)
			(type default)
		)
	)
	(wire
		(pts
			(xy 259.08 40.64) (xy 259.08 73.66)
		)
		(stroke
			(width 0)
			(type default)
		)
	)
	(wire
		(pts
			(xy 259.08 149.86) (xy 261.62 149.86)
		)
		(stroke
			(width 0)
			(type default)
		)
	)
	(wire
		(pts
			(xy 237.49 139.7) (xy 237.49 147.32)
		)
		(stroke
			(width 0)
			(type default)
		)
	)
	(wire
		(pts
			(xy 354.33 177.8) (xy 364.49 177.8)
		)
		(stroke
			(width 0)
			(type default)
		)
	)
	(wire
		(pts
			(xy 256.54 180.34) (xy 256.54 185.42)
		)
		(stroke
			(width 0)
			(type default)
		)
	)
	(wire
		(pts
			(xy 217.17 157.48) (xy 217.17 152.4)
		)
		(stroke
			(width 0)
			(type default)
		)
	)
	(wire
		(pts
			(xy 364.49 139.7) (xy 374.65 139.7)
		)
		(stroke
			(width 0)
			(type default)
		)
	)
	(wire
		(pts
			(xy 364.49 63.5) (xy 364.49 71.12)
		)
		(stroke
			(width 0)
			(type default)
		)
	)
	(wire
		(pts
			(xy 327.66 63.5) (xy 327.66 66.04)
		)
		(stroke
			(width 0)
			(type default)
		)
	)
	(wire
		(pts
			(xy 307.34 63.5) (xy 294.64 63.5)
		)
		(stroke
			(width 0)
			(type default)
		)
	)
	(wire
		(pts
			(xy 256.54 27.94) (xy 256.54 33.02)
		)
		(stroke
			(width 0)
			(type default)
		)
	)
	(wire
		(pts
			(xy 374.65 25.4) (xy 374.65 33.02)
		)
		(stroke
			(width 0)
			(type default)
		)
	)
	(wire
		(pts
			(xy 256.54 78.74) (xy 259.08 78.74)
		)
		(stroke
			(width 0)
			(type default)
		)
	)
	(wire
		(pts
			(xy 344.17 63.5) (xy 332.74 63.5)
		)
		(stroke
			(width 0)
			(type default)
		)
	)
	(wire
		(pts
			(xy 217.17 25.4) (xy 227.33 25.4)
		)
		(stroke
			(width 0)
			(type default)
		)
	)
	(wire
		(pts
			(xy 279.4 215.9) (xy 279.4 218.44)
		)
		(stroke
			(width 0)
			(type default)
		)
	)
	(wire
		(pts
			(xy 256.54 66.04) (xy 276.86 66.04)
		)
		(stroke
			(width 0)
			(type default)
		)
	)
	(wire
		(pts
			(xy 364.49 195.58) (xy 364.49 190.5)
		)
		(stroke
			(width 0)
			(type default)
		)
	)
	(wire
		(pts
			(xy 247.65 43.18) (xy 247.65 38.1)
		)
		(stroke
			(width 0)
			(type default)
		)
	)
	(wire
		(pts
			(xy 374.65 25.4) (xy 379.73 25.4)
		)
		(stroke
			(width 0)
			(type default)
		)
	)
	(wire
		(pts
			(xy 203.2 215.9) (xy 228.6 215.9)
		)
		(stroke
			(width 0)
			(type default)
		)
	)
	(wire
		(pts
			(xy 344.17 177.8) (xy 332.74 177.8)
		)
		(stroke
			(width 0)
			(type default)
		)
	)
	(wire
		(pts
			(xy 354.33 139.7) (xy 354.33 147.32)
		)
		(stroke
			(width 0)
			(type default)
		)
	)
	(wire
		(pts
			(xy 237.49 25.4) (xy 237.49 33.02)
		)
		(stroke
			(width 0)
			(type default)
		)
	)
	(wire
		(pts
			(xy 297.18 157.48) (xy 297.18 154.94)
		)
		(stroke
			(width 0)
			(type default)
		)
	)
	(wire
		(pts
			(xy 294.64 111.76) (xy 327.66 111.76)
		)
		(stroke
			(width 0)
			(type default)
		)
	)
	(wire
		(pts
			(xy 344.17 25.4) (xy 354.33 25.4)
		)
		(stroke
			(width 0)
			(type default)
		)
	)
	(wire
		(pts
			(xy 217.17 119.38) (xy 217.17 114.3)
		)
		(stroke
			(width 0)
			(type default)
		)
	)
	(wire
		(pts
			(xy 209.55 238.76) (xy 220.98 238.76)
		)
		(stroke
			(width 0)
			(type default)
		)
	)
	(wire
		(pts
			(xy 203.2 243.84) (xy 203.2 246.38)
		)
		(stroke
			(width 0)
			(type default)
		)
	)
	(wire
		(pts
			(xy 247.65 33.02) (xy 247.65 27.94)
		)
		(stroke
			(width 0)
			(type default)
		)
	)
	(wire
		(pts
			(xy 227.33 101.6) (xy 227.33 109.22)
		)
		(stroke
			(width 0)
			(type default)
		)
	)
	(wire
		(pts
			(xy 247.65 104.14) (xy 256.54 104.14)
		)
		(stroke
			(width 0)
			(type default)
		)
	)
	(wire
		(pts
			(xy 307.34 101.6) (xy 314.96 101.6)
		)
		(stroke
			(width 0)
			(type default)
		)
	)
	(wire
		(pts
			(xy 364.49 25.4) (xy 374.65 25.4)
		)
		(stroke
			(width 0)
			(type default)
		)
	)
	(wire
		(pts
			(xy 374.65 81.28) (xy 374.65 76.2)
		)
		(stroke
			(width 0)
			(type default)
		)
	)
	(wire
		(pts
			(xy 256.54 76.2) (xy 256.54 78.74)
		)
		(stroke
			(width 0)
			(type default)
		)
	)
	(wire
		(pts
			(xy 332.74 73.66) (xy 332.74 74.93)
		)
		(stroke
			(width 0)
			(type default)
		)
	)
	(wire
		(pts
			(xy 332.74 139.7) (xy 327.66 139.7)
		)
		(stroke
			(width 0)
			(type default)
		)
	)
	(wire
		(pts
			(xy 247.65 119.38) (xy 247.65 114.3)
		)
		(stroke
			(width 0)
			(type default)
		)
	)
	(wire
		(pts
			(xy 217.17 177.8) (xy 227.33 177.8)
		)
		(stroke
			(width 0)
			(type default)
		)
	)
	(wire
		(pts
			(xy 327.66 25.4) (xy 327.66 27.94)
		)
		(stroke
			(width 0)
			(type default)
		)
	)
	(wire
		(pts
			(xy 332.74 185.42) (xy 332.74 187.96)
		)
		(stroke
			(width 0)
			(type default)
		)
	)
	(wire
		(pts
			(xy 227.33 25.4) (xy 237.49 25.4)
		)
		(stroke
			(width 0)
			(type default)
		)
	)
	(wire
		(pts
			(xy 391.16 101.6) (xy 400.05 101.6)
		)
		(stroke
			(width 0)
			(type default)
		)
	)
	(wire
		(pts
			(xy 247.65 180.34) (xy 256.54 180.34)
		)
		(stroke
			(width 0)
			(type default)
		)
	)
	(wire
		(pts
			(xy 344.17 101.6) (xy 354.33 101.6)
		)
		(stroke
			(width 0)
			(type default)
		)
	)
	(wire
		(pts
			(xy 217.17 139.7) (xy 217.17 147.32)
		)
		(stroke
			(width 0)
			(type default)
		)
	)
	(wire
		(pts
			(xy 294.64 187.96) (xy 327.66 187.96)
		)
		(stroke
			(width 0)
			(type default)
		)
	)
	(wire
		(pts
			(xy 354.33 43.18) (xy 354.33 38.1)
		)
		(stroke
			(width 0)
			(type default)
		)
	)
	(wire
		(pts
			(xy 332.74 109.22) (xy 332.74 111.76)
		)
		(stroke
			(width 0)
			(type default)
		)
	)
	(wire
		(pts
			(xy 364.49 25.4) (xy 364.49 33.02)
		)
		(stroke
			(width 0)
			(type default)
		)
	)
	(wire
		(pts
			(xy 294.64 177.8) (xy 307.34 177.8)
		)
		(stroke
			(width 0)
			(type default)
		)
	)
	(wire
		(pts
			(xy 228.6 215.9) (xy 228.6 218.44)
		)
		(stroke
			(width 0)
			(type default)
		)
	)
	(wire
		(pts
			(xy 307.34 177.8) (xy 314.96 177.8)
		)
		(stroke
			(width 0)
			(type default)
		)
	)
	(wire
		(pts
			(xy 384.81 25.4) (xy 391.16 25.4)
		)
		(stroke
			(width 0)
			(type default)
		)
	)
	(wire
		(pts
			(xy 391.16 236.22) (xy 387.35 236.22)
		)
		(stroke
			(width 0)
			(type default)
		)
	)
	(wire
		(pts
			(xy 297.18 116.84) (xy 294.64 116.84)
		)
		(stroke
			(width 0)
			(type default)
		)
	)
	(wire
		(pts
			(xy 184.15 238.76) (xy 195.58 238.76)
		)
		(stroke
			(width 0)
			(type default)
		)
	)
	(wire
		(pts
			(xy 314.96 63.5) (xy 307.34 63.5)
		)
		(stroke
			(width 0)
			(type default)
		)
	)
	(wire
		(pts
			(xy 294.64 144.78) (xy 307.34 144.78)
		)
		(stroke
			(width 0)
			(type default)
		)
	)
	(wire
		(pts
			(xy 266.7 73.66) (xy 276.86 73.66)
		)
		(stroke
			(width 0)
			(type default)
		)
	)
	(wire
		(pts
			(xy 266.7 149.86) (xy 276.86 149.86)
		)
		(stroke
			(width 0)
			(type default)
		)
	)
	(wire
		(pts
			(xy 247.65 147.32) (xy 247.65 142.24)
		)
		(stroke
			(width 0)
			(type default)
		)
	)
	(wire
		(pts
			(xy 314.96 240.03) (xy 314.96 205.74)
		)
		(stroke
			(width 0)
			(type default)
		)
	)
	(wire
		(pts
			(xy 364.49 63.5) (xy 374.65 63.5)
		)
		(stroke
			(width 0)
			(type default)
		)
	)
	(wire
		(pts
			(xy 388.62 241.3) (xy 391.16 241.3)
		)
		(stroke
			(width 0)
			(type default)
		)
	)
	(wire
		(pts
			(xy 217.17 63.5) (xy 217.17 71.12)
		)
		(stroke
			(width 0)
			(type default)
		)
	)
	(wire
		(pts
			(xy 217.17 175.26) (xy 217.17 177.8)
		)
		(stroke
			(width 0)
			(type default)
		)
	)
	(wire
		(pts
			(xy 332.74 101.6) (xy 344.17 101.6)
		)
		(stroke
			(width 0)
			(type default)
		)
	)
	(wire
		(pts
			(xy 332.74 156.21) (xy 332.74 157.48)
		)
		(stroke
			(width 0)
			(type default)
		)
	)
	(wire
		(pts
			(xy 391.16 22.86) (xy 391.16 25.4)
		)
		(stroke
			(width 0)
			(type default)
		)
	)
	(wire
		(pts
			(xy 294.64 25.4) (xy 307.34 25.4)
		)
		(stroke
			(width 0)
			(type default)
		)
	)
	(wire
		(pts
			(xy 391.16 137.16) (xy 391.16 139.7)
		)
		(stroke
			(width 0)
			(type default)
		)
	)
	(wire
		(pts
			(xy 260.35 238.76) (xy 271.78 238.76)
		)
		(stroke
			(width 0)
			(type default)
		)
	)
	(wire
		(pts
			(xy 247.65 195.58) (xy 247.65 190.5)
		)
		(stroke
			(width 0)
			(type default)
		)
	)
	(wire
		(pts
			(xy 391.16 175.26) (xy 391.16 177.8)
		)
		(stroke
			(width 0)
			(type default)
		)
	)
	(wire
		(pts
			(xy 237.49 101.6) (xy 276.86 101.6)
		)
		(stroke
			(width 0)
			(type default)
		)
	)
	(wire
		(pts
			(xy 217.17 63.5) (xy 227.33 63.5)
		)
		(stroke
			(width 0)
			(type default)
		)
	)
	(wire
		(pts
			(xy 374.65 139.7) (xy 374.65 147.32)
		)
		(stroke
			(width 0)
			(type default)
		)
	)
	(wire
		(pts
			(xy 344.17 119.38) (xy 344.17 114.3)
		)
		(stroke
			(width 0)
			(type default)
		)
	)
	(wire
		(pts
			(xy 297.18 40.64) (xy 294.64 40.64)
		)
		(stroke
			(width 0)
			(type default)
		)
	)
	(wire
		(pts
			(xy 364.49 43.18) (xy 364.49 38.1)
		)
		(stroke
			(width 0)
			(type default)
		)
	)
	(wire
		(pts
			(xy 254 233.68) (xy 254 231.14)
		)
		(stroke
			(width 0)
			(type default)
		)
	)
	(wire
		(pts
			(xy 237.49 63.5) (xy 237.49 71.12)
		)
		(stroke
			(width 0)
			(type default)
		)
	)
	(wire
		(pts
			(xy 354.33 119.38) (xy 354.33 114.3)
		)
		(stroke
			(width 0)
			(type default)
		)
	)
	(wire
		(pts
			(xy 203.2 233.68) (xy 203.2 231.14)
		)
		(stroke
			(width 0)
			(type default)
		)
	)
	(wire
		(pts
			(xy 304.8 215.9) (xy 304.8 217.17)
		)
		(stroke
			(width 0)
			(type default)
		)
	)
	(wire
		(pts
			(xy 227.33 81.28) (xy 227.33 76.2)
		)
		(stroke
			(width 0)
			(type default)
		)
	)
	(wire
		(pts
			(xy 374.65 139.7) (xy 379.73 139.7)
		)
		(stroke
			(width 0)
			(type default)
		)
	)
	(wire
		(pts
			(xy 344.17 81.28) (xy 344.17 76.2)
		)
		(stroke
			(width 0)
			(type default)
		)
	)
	(wire
		(pts
			(xy 177.8 231.14) (xy 177.8 246.38)
		)
		(stroke
			(width 0)
			(type default)
		)
	)
	(wire
		(pts
			(xy 256.54 154.94) (xy 259.08 154.94)
		)
		(stroke
			(width 0)
			(type default)
		)
	)
	(wire
		(pts
			(xy 391.16 177.8) (xy 400.05 177.8)
		)
		(stroke
			(width 0)
			(type default)
		)
	)
	(wire
		(pts
			(xy 391.16 60.96) (xy 391.16 63.5)
		)
		(stroke
			(width 0)
			(type default)
		)
	)
	(wire
		(pts
			(xy 312.42 240.03) (xy 314.96 240.03)
		)
		(stroke
			(width 0)
			(type default)
		)
	)
	(wire
		(pts
			(xy 259.08 154.94) (xy 259.08 187.96)
		)
		(stroke
			(width 0)
			(type default)
		)
	)
	(wire
		(pts
			(xy 374.65 101.6) (xy 379.73 101.6)
		)
		(stroke
			(width 0)
			(type default)
		)
	)
	(wire
		(pts
			(xy 294.64 149.86) (xy 327.66 149.86)
		)
		(stroke
			(width 0)
			(type default)
		)
	)
	(wire
		(pts
			(xy 297.18 43.18) (xy 297.18 40.64)
		)
		(stroke
			(width 0)
			(type default)
		)
	)
	(wire
		(pts
			(xy 400.05 177.8) (xy 400.05 175.26)
		)
		(stroke
			(width 0)
			(type default)
		)
	)
	(wire
		(pts
			(xy 297.18 81.28) (xy 297.18 78.74)
		)
		(stroke
			(width 0)
			(type default)
		)
	)
	(wire
		(pts
			(xy 279.4 243.84) (xy 279.4 246.38)
		)
		(stroke
			(width 0)
			(type default)
		)
	)
	(wire
		(pts
			(xy 228.6 233.68) (xy 228.6 231.14)
		)
		(stroke
			(width 0)
			(type default)
		)
	)
	(wire
		(pts
			(xy 256.54 38.1) (xy 256.54 40.64)
		)
		(stroke
			(width 0)
			(type default)
		)
	)
	(wire
		(pts
			(xy 247.65 109.22) (xy 247.65 104.14)
		)
		(stroke
			(width 0)
			(type default)
		)
	)
	(wire
		(pts
			(xy 384.81 63.5) (xy 391.16 63.5)
		)
		(stroke
			(width 0)
			(type default)
		)
	)
	(wire
		(pts
			(xy 227.33 63.5) (xy 237.49 63.5)
		)
		(stroke
			(width 0)
			(type default)
		)
	)
	(wire
		(pts
			(xy 327.66 187.96) (xy 332.74 187.96)
		)
		(stroke
			(width 0)
			(type default)
		)
	)
	(wire
		(pts
			(xy 332.74 101.6) (xy 332.74 104.14)
		)
		(stroke
			(width 0)
			(type default)
		)
	)
	(wire
		(pts
			(xy 304.8 243.84) (xy 304.8 246.38)
		)
		(stroke
			(width 0)
			(type default)
		)
	)
	(wire
		(pts
			(xy 237.49 177.8) (xy 276.86 177.8)
		)
		(stroke
			(width 0)
			(type default)
		)
	)
	(wire
		(pts
			(xy 344.17 177.8) (xy 344.17 185.42)
		)
		(stroke
			(width 0)
			(type default)
		)
	)
	(wire
		(pts
			(xy 344.17 177.8) (xy 354.33 177.8)
		)
		(stroke
			(width 0)
			(type default)
		)
	)
	(wire
		(pts
			(xy 374.65 43.18) (xy 374.65 38.1)
		)
		(stroke
			(width 0)
			(type default)
		)
	)
	(wire
		(pts
			(xy 374.65 195.58) (xy 374.65 190.5)
		)
		(stroke
			(width 0)
			(type default)
		)
	)
	(wire
		(pts
			(xy 227.33 25.4) (xy 227.33 33.02)
		)
		(stroke
			(width 0)
			(type default)
		)
	)
	(wire
		(pts
			(xy 332.74 101.6) (xy 327.66 101.6)
		)
		(stroke
			(width 0)
			(type default)
		)
	)
	(wire
		(pts
			(xy 327.66 35.56) (xy 332.74 35.56)
		)
		(stroke
			(width 0)
			(type default)
		)
	)
	(wire
		(pts
			(xy 332.74 139.7) (xy 344.17 139.7)
		)
		(stroke
			(width 0)
			(type default)
		)
	)
	(table
		(column_count 1)
		(border
			(external yes)
			(header yes)
			(stroke
				(width 0)
				(type solid)
			)
		)
		(separators
			(rows yes)
			(cols yes)
			(stroke
				(width 0)
				(type solid)
			)
		)
		(column_widths 66.04)
		(row_heights 2.54 5.08)
		(cells
			(table_cell "POWER SEQUENCING"
				(exclude_from_sim no)
				(at 207.01 13.97 0)
				(size 66.04 2.54)
				(margins 0.9525 0.9525 0.9525 0.9525)
				(span 1 1)
				(fill
					(type none)
				)
				(effects
					(font
						(size 1.27 1.27)
					)
				)
			)
			(table_cell ""
				(exclude_from_sim no)
				(at 207.01 16.51 0)
				(size 66.04 5.08)
				(margins 0.9525 0.9525 0.9525 0.9525)
				(span 1 1)
				(fill
					(type none)
				)
				(effects
					(font
						(size 1.27 1.27)
					)
					(justify left top)
				)
			)
		)
	)
	(label "VCCD_SW"
		(at 294.64 63.5 0)
		(effects
			(font
				(size 1.27 1.27)
			)
			(justify left bottom)
		)
	)
	(label "1V0_BST"
		(at 294.64 144.78 0)
		(effects
			(font
				(size 1.27 1.27)
			)
			(justify left bottom)
		)
	)
	(label "+3V3_OUT"
		(at 166.37 215.9 0)
		(effects
			(font
				(size 1.27 1.27)
			)
			(justify left bottom)
		)
	)
	(label "DVDD_EN"
		(at 276.86 187.96 180)
		(effects
			(font
				(size 1.27 1.27)
			)
			(justify right bottom)
		)
	)
	(label "+DVDD_OUT"
		(at 344.17 177.8 180)
		(effects
			(font
				(size 1.27 1.27)
			)
			(justify right bottom)
		)
	)
	(label "1V0_FB"
		(at 294.64 149.86 0)
		(effects
			(font
				(size 1.27 1.27)
			)
			(justify left bottom)
		)
	)
	(label "1V88_SW"
		(at 294.64 101.6 0)
		(effects
			(font
				(size 1.27 1.27)
			)
			(justify left bottom)
		)
	)
	(label "VCCD_VCC"
		(at 276.86 66.04 180)
		(effects
			(font
				(size 1.27 1.27)
			)
			(justify right bottom)
		)
	)
	(label "3V3_BST"
		(at 294.64 30.48 0)
		(effects
			(font
				(size 1.27 1.27)
			)
			(justify left bottom)
		)
	)
	(label "1V88_BST"
		(at 294.64 106.68 0)
		(effects
			(font
				(size 1.27 1.27)
			)
			(justify left bottom)
		)
	)
	(label "3V3_VCC"
		(at 276.86 27.94 180)
		(effects
			(font
				(size 1.27 1.27)
			)
			(justify right bottom)
		)
	)
	(label "DVDD_FB"
		(at 294.64 187.96 0)
		(effects
			(font
				(size 1.27 1.27)
			)
			(justify left bottom)
		)
	)
	(label "+1V0_OUT"
		(at 234.95 238.76 0)
		(effects
			(font
				(size 1.27 1.27)
			)
			(justify left bottom)
		)
	)
	(label "1V88_EN"
		(at 276.86 111.76 180)
		(effects
			(font
				(size 1.27 1.27)
			)
			(justify right bottom)
		)
	)
	(label "+VCCD_OUT"
		(at 184.15 238.76 0)
		(effects
			(font
				(size 1.27 1.27)
			)
			(justify left bottom)
		)
	)
	(label "1V0_VCC"
		(at 276.86 142.24 180)
		(effects
			(font
				(size 1.27 1.27)
			)
			(justify right bottom)
		)
	)
	(label "+VCCD_OUT"
		(at 344.17 63.5 180)
		(effects
			(font
				(size 1.27 1.27)
			)
			(justify right bottom)
		)
	)
	(label "DVDD_PG"
		(at 276.86 193.04 180)
		(effects
			(font
				(size 1.27 1.27)
			)
			(justify right bottom)
		)
	)
	(label "DVDD_SW"
		(at 294.64 177.8 0)
		(effects
			(font
				(size 1.27 1.27)
			)
			(justify left bottom)
		)
	)
	(label "1V0_PG"
		(at 276.86 154.94 180)
		(effects
			(font
				(size 1.27 1.27)
			)
			(justify right bottom)
		)
	)
	(label "+3V3_OUT"
		(at 344.17 25.4 180)
		(effects
			(font
				(size 1.27 1.27)
			)
			(justify right bottom)
		)
	)
	(label "+1V0_OUT"
		(at 344.17 139.7 180)
		(effects
			(font
				(size 1.27 1.27)
			)
			(justify right bottom)
		)
	)
	(label "DVDD_VCC"
		(at 276.86 180.34 180)
		(effects
			(font
				(size 1.27 1.27)
			)
			(justify right bottom)
		)
	)
	(label "1V88_VCC"
		(at 276.86 104.14 180)
		(effects
			(font
				(size 1.27 1.27)
			)
			(justify right bottom)
		)
	)
	(label "+1V88_OUT"
		(at 209.55 238.76 0)
		(effects
			(font
				(size 1.27 1.27)
			)
			(justify left bottom)
		)
	)
	(label "VCCD_BST"
		(at 294.64 68.58 0)
		(effects
			(font
				(size 1.27 1.27)
			)
			(justify left bottom)
		)
	)
	(label "1V0_SW"
		(at 294.64 139.7 0)
		(effects
			(font
				(size 1.27 1.27)
			)
			(justify left bottom)
		)
	)
	(label "3V3_FB"
		(at 294.64 35.56 0)
		(effects
			(font
				(size 1.27 1.27)
			)
			(justify left bottom)
		)
	)
	(label "DVDD_BST"
		(at 294.64 182.88 0)
		(effects
			(font
				(size 1.27 1.27)
			)
			(justify left bottom)
		)
	)
	(label "VCCD_FB"
		(at 294.64 73.66 0)
		(effects
			(font
				(size 1.27 1.27)
			)
			(justify left bottom)
		)
	)
	(label "1V88_FB"
		(at 294.64 111.76 0)
		(effects
			(font
				(size 1.27 1.27)
			)
			(justify left bottom)
		)
	)
	(label "3V3_PG"
		(at 276.86 40.64 180)
		(effects
			(font
				(size 1.27 1.27)
			)
			(justify right bottom)
		)
	)
	(label "3V3_SW"
		(at 294.64 25.4 0)
		(effects
			(font
				(size 1.27 1.27)
			)
			(justify left bottom)
		)
	)
	(label "1V88_PG"
		(at 276.86 116.84 180)
		(effects
			(font
				(size 1.27 1.27)
			)
			(justify right bottom)
		)
	)
	(label "VCCD_EN"
		(at 276.86 73.66 180)
		(effects
			(font
				(size 1.27 1.27)
			)
			(justify right bottom)
		)
	)
	(label "+1V88_OUT"
		(at 344.17 101.6 180)
		(effects
			(font
				(size 1.27 1.27)
			)
			(justify right bottom)
		)
	)
	(label "+DVDD_OUT"
		(at 260.35 238.76 0)
		(effects
			(font
				(size 1.27 1.27)
			)
			(justify left bottom)
		)
	)
	(label "VCCD_PG"
		(at 276.86 78.74 180)
		(effects
			(font
				(size 1.27 1.27)
			)
			(justify right bottom)
		)
	)
	(label "1V0_EN"
		(at 276.86 149.86 180)
		(effects
			(font
				(size 1.27 1.27)
			)
			(justify right bottom)
		)
	)
	(hierarchical_label "EN"
		(shape input)
		(at 273.05 35.56 180)
		(effects
			(font
				(size 1.27 1.27)
			)
			(justify right)
		)
	)
	(symbol
		(lib_id "antmicroResistors0402:R_0R_0402")
		(at 261.62 187.96 0)
		(unit 1)
		(exclude_from_sim no)
		(in_bom yes)
		(on_board yes)
		(dnp no)
		(property "Reference" "R95"
			(at 264.16 185.674 0)
			(effects
				(font
					(size 1.27 1.27)
					(thickness 0.15)
				)
			)
		)
		(property "Value" "R_0R_0402"
			(at 281.94 200.66 0)
			(effects
				(font
					(size 1.27 1.27)
					(thickness 0.15)
				)
				(justify left bottom)
				(hide yes)
			)
		)
		(property "Footprint" "antmicro-footprints:R_0402_1005Metric"
			(at 281.94 203.2 0)
			(effects
				(font
					(size 1.27 1.27)
					(thickness 0.15)
				)
				(justify left bottom)
				(hide yes)
			)
		)
		(property "Datasheet" "https://industrial.panasonic.com/cdbs/www-data/pdf/RDA0000/AOA0000C301.pdf"
			(at 281.94 205.74 0)
			(effects
				(font
					(size 1.27 1.27)
					(thickness 0.15)
				)
				(justify left bottom)
				(hide yes)
			)
		)
		(property "Description" "SMD Chip Resistor, Jumper, 0 ohm, 100 mW, 0402 [1005 Metric], Thick Film, General Purpose"
			(at 281.94 220.98 0)
			(effects
				(font
					(size 1.27 1.27)
				)
				(justify left bottom)
				(hide yes)
			)
		)
		(property "MPN" "ERJ2GE0R00X"
			(at 281.94 208.28 0)
			(effects
				(font
					(size 1.27 1.27)
					(thickness 0.15)
				)
				(justify left bottom)
				(hide yes)
			)
		)
		(property "Manufacturer" "Panasonic"
			(at 281.94 210.82 0)
			(effects
				(font
					(size 1.27 1.27)
					(thickness 0.15)
				)
				(justify left bottom)
				(hide yes)
			)
		)
		(property "License" "Apache-2.0"
			(at 281.94 213.36 0)
			(effects
				(font
					(size 1.27 1.27)
					(thickness 0.15)
				)
				(justify left bottom)
				(hide yes)
			)
		)
		(property "Author" "Antmicro"
			(at 281.94 215.9 0)
			(effects
				(font
					(size 1.27 1.27)
					(thickness 0.15)
				)
				(justify left bottom)
				(hide yes)
			)
		)
		(property "Val" "0R"
			(at 264.16 190.246 0)
			(effects
				(font
					(size 1.27 1.27)
					(thickness 0.15)
				)
			)
		)
		(property "Tolerance" "~"
			(at 281.94 198.12 0)
			(effects
				(font
					(size 1.27 1.27)
				)
				(justify left bottom)
				(hide yes)
			)
		)
		(property "Current" "1A"
			(at 281.94 218.44 0)
			(effects
				(font
					(size 1.27 1.27)
					(thickness 0.15)
				)
				(justify left bottom)
				(hide yes)
			)
		)
		(pin "2"
		)
		(pin "1"
		)
		(instances
			(project "thunderbolt-to-10gbe-adapter"
				(path ""
					(reference "R95")
					(unit 1)
				)
			)
		)
	)
	(symbol
		(lib_id "antmicroCapacitors0603:C_22u_16V_0603")
		(at 364.49 190.5 90)
		(unit 1)
		(exclude_from_sim no)
		(in_bom yes)
		(on_board yes)
		(dnp no)
		(property "Reference" "C148"
			(at 366.268 186.69 90)
			(effects
				(font
					(size 1.27 1.27)
					(thickness 0.15)
				)
				(justify right)
			)
		)
		(property "Value" "C_22u_16V_0603"
			(at 374.65 170.18 0)
			(effects
				(font
					(size 1.27 1.27)
					(thickness 0.15)
				)
				(justify left bottom)
				(hide yes)
			)
		)
		(property "Footprint" "antmicro-footprints:C_0603_1608Metric_EIA"
			(at 377.19 170.18 0)
			(effects
				(font
					(size 1.27 1.27)
					(thickness 0.15)
				)
				(justify left bottom)
				(hide yes)
			)
		)
		(property "Datasheet" "https://product.samsungsem.com/mlcc/CL10A226MO7JZN.do"
			(at 379.73 170.18 0)
			(effects
				(font
					(size 1.27 1.27)
					(thickness 0.15)
				)
				(justify left bottom)
				(hide yes)
			)
		)
		(property "Description" "SMD Multilayer Ceramic Capacitor"
			(at 364.49 190.5 0)
			(effects
				(font
					(size 1.27 1.27)
				)
				(hide yes)
			)
		)
		(property "MPN" "CL10A226MO7JZNC"
			(at 382.27 170.18 0)
			(effects
				(font
					(size 1.27 1.27)
					(thickness 0.15)
				)
				(justify left bottom)
				(hide yes)
			)
		)
		(property "Manufacturer" "Samsung Electro-Mechanics"
			(at 384.81 170.18 0)
			(effects
				(font
					(size 1.27 1.27)
					(thickness 0.15)
				)
				(justify left bottom)
				(hide yes)
			)
		)
		(property "License" "Apache-2.0"
			(at 387.35 170.18 0)
			(effects
				(font
					(size 1.27 1.27)
					(thickness 0.15)
				)
				(justify left bottom)
				(hide yes)
			)
		)
		(property "Author" "Antmicro"
			(at 389.89 170.18 0)
			(effects
				(font
					(size 1.27 1.27)
					(thickness 0.15)
				)
				(justify left bottom)
				(hide yes)
			)
		)
		(property "Val" "22u"
			(at 366.268 189.23 90)
			(effects
				(font
					(size 1.27 1.27)
					(thickness 0.15)
				)
				(justify right)
			)
		)
		(property "Voltage" "16V"
			(at 367.03 190.4935 90)
			(effects
				(font
					(size 1.27 1.27)
				)
				(justify right)
				(hide yes)
			)
		)
		(property "Dielectric" ""
			(at 394.97 170.18 0)
			(effects
				(font
					(size 1.27 1.27)
				)
				(justify left bottom)
				(hide yes)
			)
		)
		(pin "2"
		)
		(pin "1"
		)
		(instances
			(project "thunderbolt-to-10gbe-adapter"
				(path ""
					(reference "C148")
					(unit 1)
				)
			)
		)
	)
	(symbol
		(lib_id "antmicroCapacitors0402:C_1u_25V_0402")
		(at 247.65 152.4 270)
		(mirror x)
		(unit 1)
		(exclude_from_sim no)
		(in_bom yes)
		(on_board yes)
		(dnp no)
		(property "Reference" "C122"
			(at 245.872 148.59 90)
			(effects
				(font
					(size 1.27 1.27)
					(thickness 0.15)
				)
				(justify right)
			)
		)
		(property "Value" "C_1u_25V_0402"
			(at 237.49 132.08 0)
			(effects
				(font
					(size 1.27 1.27)
					(thickness 0.15)
				)
				(justify left bottom)
				(hide yes)
			)
		)
		(property "Footprint" "antmicro-footprints:C_0402_1005Metric"
			(at 234.95 132.08 0)
			(effects
				(font
					(size 1.27 1.27)
					(thickness 0.15)
				)
				(justify left bottom)
				(hide yes)
			)
		)
		(property "Datasheet" "https://www.murata.com/products/productdetail?partno=GRM155R61E105KE11%23"
			(at 232.41 132.08 0)
			(effects
				(font
					(size 1.27 1.27)
					(thickness 0.15)
				)
				(justify left bottom)
				(hide yes)
			)
		)
		(property "Description" "SMD Multilayer Ceramic Capacitor, 1 µF, 25 V, 0402 [1005 Metric], ± 10%, X5R, GRM Series"
			(at 214.63 132.08 0)
			(effects
				(font
					(size 1.27 1.27)
				)
				(justify left bottom)
				(hide yes)
			)
		)
		(property "MPN" "GRM155R61E105KE11J"
			(at 229.87 132.08 0)
			(effects
				(font
					(size 1.27 1.27)
					(thickness 0.15)
				)
				(justify left bottom)
				(hide yes)
			)
		)
		(property "Manufacturer" "Murata"
			(at 227.33 132.08 0)
			(effects
				(font
					(size 1.27 1.27)
					(thickness 0.15)
				)
				(justify left bottom)
				(hide yes)
			)
		)
		(property "License" "Apache-2.0"
			(at 224.79 132.08 0)
			(effects
				(font
					(size 1.27 1.27)
					(thickness 0.15)
				)
				(justify left bottom)
				(hide yes)
			)
		)
		(property "Author" "Antmicro"
			(at 222.25 132.08 0)
			(effects
				(font
					(size 1.27 1.27)
					(thickness 0.15)
				)
				(justify left bottom)
				(hide yes)
			)
		)
		(property "Val" "1u"
			(at 245.872 151.13 90)
			(effects
				(font
					(size 1.27 1.27)
					(thickness 0.15)
				)
				(justify right)
			)
		)
		(property "Voltage" "25V"
			(at 219.71 132.08 0)
			(effects
				(font
					(size 1.27 1.27)
				)
				(justify left bottom)
				(hide yes)
			)
		)
		(property "Dielectric" "X5R"
			(at 217.17 132.08 0)
			(effects
				(font
					(size 1.27 1.27)
				)
				(justify left bottom)
				(hide yes)
			)
		)
		(pin "2"
		)
		(pin "1"
		)
		(instances
			(project "thunderbolt-to-10gbe-adapter"
				(path ""
					(reference "C122")
					(unit 1)
				)
			)
		)
	)
	(symbol
		(lib_id "antmicropower:GND")
		(at 227.33 119.38 0)
		(unit 1)
		(exclude_from_sim no)
		(in_bom yes)
		(on_board yes)
		(dnp no)
		(property "Reference" "#PWR0161"
			(at 236.22 121.92 0)
			(effects
				(font
					(size 1.27 1.27)
					(thickness 0.15)
				)
				(justify left bottom)
				(hide yes)
			)
		)
		(property "Value" "GND"
			(at 227.33 123.19 0)
			(effects
				(font
					(size 1.27 1.27)
					(thickness 0.15)
				)
			)
		)
		(property "Footprint" ""
			(at 236.22 127 0)
			(effects
				(font
					(size 1.27 1.27)
					(thickness 0.15)
				)
				(justify left bottom)
				(hide yes)
			)
		)
		(property "Datasheet" ""
			(at 236.22 132.08 0)
			(effects
				(font
					(size 1.27 1.27)
					(thickness 0.15)
				)
				(justify left bottom)
				(hide yes)
			)
		)
		(property "Description" ""
			(at 227.33 119.38 0)
			(effects
				(font
					(size 1.27 1.27)
				)
				(hide yes)
			)
		)
		(property "Author" "Antmicro"
			(at 236.22 127 0)
			(effects
				(font
					(size 1.27 1.27)
					(thickness 0.15)
				)
				(justify left bottom)
				(hide yes)
			)
		)
		(property "License" "Apache-2.0"
			(at 236.22 129.54 0)
			(effects
				(font
					(size 1.27 1.27)
					(thickness 0.15)
				)
				(justify left bottom)
				(hide yes)
			)
		)
		(pin "1"
		)
		(instances
			(project "thunderbolt-to-10gbe-adapter"
				(path ""
					(reference "#PWR0161")
					(unit 1)
				)
			)
		)
	)
	(symbol
		(lib_id "antmicroCapacitors0603:C_22u_16V_0603")
		(at 354.33 38.1 90)
		(unit 1)
		(exclude_from_sim no)
		(in_bom yes)
		(on_board yes)
		(dnp no)
		(property "Reference" "C139"
			(at 356.108 34.29 90)
			(effects
				(font
					(size 1.27 1.27)
					(thickness 0.15)
				)
				(justify right)
			)
		)
		(property "Value" "C_22u_16V_0603"
			(at 364.49 17.78 0)
			(effects
				(font
					(size 1.27 1.27)
					(thickness 0.15)
				)
				(justify left bottom)
				(hide yes)
			)
		)
		(property "Footprint" "antmicro-footprints:C_0603_1608Metric_EIA"
			(at 367.03 17.78 0)
			(effects
				(font
					(size 1.27 1.27)
					(thickness 0.15)
				)
				(justify left bottom)
				(hide yes)
			)
		)
		(property "Datasheet" "https://product.samsungsem.com/mlcc/CL10A226MO7JZN.do"
			(at 369.57 17.78 0)
			(effects
				(font
					(size 1.27 1.27)
					(thickness 0.15)
				)
				(justify left bottom)
				(hide yes)
			)
		)
		(property "Description" "SMD Multilayer Ceramic Capacitor"
			(at 354.33 38.1 0)
			(effects
				(font
					(size 1.27 1.27)
				)
				(hide yes)
			)
		)
		(property "MPN" "CL10A226MO7JZNC"
			(at 372.11 17.78 0)
			(effects
				(font
					(size 1.27 1.27)
					(thickness 0.15)
				)
				(justify left bottom)
				(hide yes)
			)
		)
		(property "Manufacturer" "Samsung Electro-Mechanics"
			(at 374.65 17.78 0)
			(effects
				(font
					(size 1.27 1.27)
					(thickness 0.15)
				)
				(justify left bottom)
				(hide yes)
			)
		)
		(property "License" "Apache-2.0"
			(at 377.19 17.78 0)
			(effects
				(font
					(size 1.27 1.27)
					(thickness 0.15)
				)
				(justify left bottom)
				(hide yes)
			)
		)
		(property "Author" "Antmicro"
			(at 379.73 17.78 0)
			(effects
				(font
					(size 1.27 1.27)
					(thickness 0.15)
				)
				(justify left bottom)
				(hide yes)
			)
		)
		(property "Val" "22u"
			(at 356.108 36.83 90)
			(effects
				(font
					(size 1.27 1.27)
					(thickness 0.15)
				)
				(justify right)
			)
		)
		(property "Voltage" "16V"
			(at 356.87 38.0935 90)
			(effects
				(font
					(size 1.27 1.27)
				)
				(justify right)
				(hide yes)
			)
		)
		(property "Dielectric" ""
			(at 384.81 17.78 0)
			(effects
				(font
					(size 1.27 1.27)
				)
				(justify left bottom)
				(hide yes)
			)
		)
		(pin "2"
		)
		(pin "1"
		)
		(instances
			(project "thunderbolt-to-10gbe-adapter"
				(path ""
					(reference "C139")
					(unit 1)
				)
			)
		)
	)
	(symbol
		(lib_id "antmicroFixedInductors:L_1u_10A_Bourns-SRP4021HMT")
		(at 314.96 63.5 0)
		(unit 1)
		(exclude_from_sim no)
		(in_bom yes)
		(on_board yes)
		(dnp no)
		(fields_autoplaced yes)
		(property "Reference" "L5"
			(at 317.5 58.42 0)
			(effects
				(font
					(size 1.27 1.27)
					(thickness 0.15)
				)
			)
		)
		(property "Value" "L_1u_10A_Bourns-SRP4021HMT"
			(at 330.2 73.66 0)
			(effects
				(font
					(size 1.27 1.27)
					(thickness 0.15)
				)
				(justify left bottom)
				(hide yes)
			)
		)
		(property "Footprint" "antmicro-footprints:L_Bourns-SRP4021HMT"
			(at 330.2 76.2 0)
			(effects
				(font
					(size 1.27 1.27)
					(thickness 0.15)
				)
				(justify left bottom)
				(hide yes)
			)
		)
		(property "Datasheet" "https://www.mouser.com/datasheet/2/54/Bourns_04_01_2025_SRP4021HMT_Datasheet-3580094.pdf"
			(at 330.2 78.74 0)
			(effects
				(font
					(size 1.27 1.27)
					(thickness 0.15)
				)
				(justify left bottom)
				(hide yes)
			)
		)
		(property "Description" "Power Inductors - SMD Ind,4.1x4.2x1.9mm,1uH+/-20%,10A, Shielded"
			(at 330.2 81.28 0)
			(effects
				(font
					(size 1.27 1.27)
					(thickness 0.15)
				)
				(justify left bottom)
				(hide yes)
			)
		)
		(property "Val" "1u/10A"
			(at 317.5 60.96 0)
			(effects
				(font
					(size 1.27 1.27)
					(thickness 0.15)
				)
			)
		)
		(property "Manufacturer" "Bourns"
			(at 330.2 83.82 0)
			(effects
				(font
					(size 1.27 1.27)
					(thickness 0.15)
				)
				(justify left bottom)
				(hide yes)
			)
		)
		(property "MPN" "SRP4021HMT-1R0M"
			(at 330.2 86.36 0)
			(effects
				(font
					(size 1.27 1.27)
					(thickness 0.15)
				)
				(justify left bottom)
				(hide yes)
			)
		)
		(property "ISat" ""
			(at 328.93 80.01 0)
			(effects
				(font
					(size 1.27 1.27)
				)
				(justify left)
				(hide yes)
			)
		)
		(property "Isat" "8A"
			(at 330.2 88.9 0)
			(effects
				(font
					(size 1.27 1.27)
					(thickness 0.15)
				)
				(justify left bottom)
				(hide yes)
			)
		)
		(property "IMax" ""
			(at 328.93 83.82 0)
			(effects
				(font
					(size 1.27 1.27)
					(thickness 0.15)
				)
				(justify left bottom)
				(hide yes)
			)
		)
		(property "Imax" "10A"
			(at 330.2 91.44 0)
			(effects
				(font
					(size 1.27 1.27)
					(thickness 0.15)
				)
				(justify left bottom)
				(hide yes)
			)
		)
		(property "Size" "4.2x4.1"
			(at 330.2 93.98 0)
			(effects
				(font
					(size 1.27 1.27)
					(thickness 0.15)
				)
				(justify left bottom)
				(hide yes)
			)
		)
		(property "Author" "Antmicro"
			(at 330.2 96.52 0)
			(effects
				(font
					(size 1.27 1.27)
					(thickness 0.15)
				)
				(justify left bottom)
				(hide yes)
			)
		)
		(property "License" "Apache-2.0"
			(at 330.2 99.06 0)
			(effects
				(font
					(size 1.27 1.27)
					(thickness 0.15)
				)
				(justify left bottom)
				(hide yes)
			)
		)
		(pin "1"
		)
		(pin "2"
		)
		(instances
			(project "thunderbolt-to-10gbe-adapter"
				(path ""
					(reference "L5")
					(unit 1)
				)
			)
		)
	)
	(symbol
		(lib_id "antmicroDCDCConverters:TPS566231P")
		(at 276.86 25.4 0)
		(unit 1)
		(exclude_from_sim no)
		(in_bom yes)
		(on_board yes)
		(dnp no)
		(fields_autoplaced yes)
		(property "Reference" "U9"
			(at 285.75 19.05 0)
			(effects
				(font
					(size 1.27 1.27)
					(thickness 0.15)
				)
			)
		)
		(property "Value" "TPS566231P"
			(at 309.88 30.48 0)
			(effects
				(font
					(size 1.27 1.27)
					(thickness 0.15)
				)
				(justify left bottom)
				(hide yes)
			)
		)
		(property "Footprint" "antmicro-footprints:VQFN-HR-9_2x1.5mm"
			(at 309.88 33.02 0)
			(effects
				(font
					(size 1.27 1.27)
					(thickness 0.15)
				)
				(justify left bottom)
				(hide yes)
			)
		)
		(property "Datasheet" "https://www.ti.com/lit/ds/symlink/tps566231.pdf"
			(at 309.88 35.56 0)
			(effects
				(font
					(size 1.27 1.27)
					(thickness 0.15)
				)
				(justify left bottom)
				(hide yes)
			)
		)
		(property "Description" "Switching Voltage Regulators 3-V to 18-V, 6-A synchronous buck converter"
			(at 309.88 48.26 0)
			(effects
				(font
					(size 1.27 1.27)
				)
				(justify left bottom)
				(hide yes)
			)
		)
		(property "Manufacturer" "Texas Instruments"
			(at 309.88 38.1 0)
			(effects
				(font
					(size 1.27 1.27)
					(thickness 0.15)
				)
				(justify left bottom)
				(hide yes)
			)
		)
		(property "MPN" "TPS566231PRQFR"
			(at 285.75 21.59 0)
			(effects
				(font
					(size 1.27 1.27)
					(thickness 0.15)
				)
			)
		)
		(property "Author" "Antmicro"
			(at 309.88 43.18 0)
			(effects
				(font
					(size 1.27 1.27)
					(thickness 0.15)
				)
				(justify left bottom)
				(hide yes)
			)
		)
		(property "License" "Apache-2.0"
			(at 309.88 45.72 0)
			(effects
				(font
					(size 1.27 1.27)
					(thickness 0.15)
				)
				(justify left bottom)
				(hide yes)
			)
		)
		(pin "1"
		)
		(pin "2"
		)
		(pin "3"
		)
		(pin "9"
		)
		(pin "5"
		)
		(pin "6"
		)
		(pin "8"
		)
		(pin "4"
		)
		(pin "7"
		)
		(instances
			(project "thunderbolt-to-10gbe-adapter"
				(path ""
					(reference "U9")
					(unit 1)
				)
			)
		)
	)
	(symbol
		(lib_id "antmicroCapacitors0603:C_22u_16V_0603")
		(at 227.33 190.5 270)
		(mirror x)
		(unit 1)
		(exclude_from_sim no)
		(in_bom yes)
		(on_board yes)
		(dnp no)
		(property "Reference" "C113"
			(at 225.552 186.69 90)
			(effects
				(font
					(size 1.27 1.27)
					(thickness 0.15)
				)
				(justify right)
			)
		)
		(property "Value" "C_22u_16V_0603"
			(at 217.17 170.18 0)
			(effects
				(font
					(size 1.27 1.27)
					(thickness 0.15)
				)
				(justify left bottom)
				(hide yes)
			)
		)
		(property "Footprint" "antmicro-footprints:C_0603_1608Metric_EIA"
			(at 214.63 170.18 0)
			(effects
				(font
					(size 1.27 1.27)
					(thickness 0.15)
				)
				(justify left bottom)
				(hide yes)
			)
		)
		(property "Datasheet" "https://product.samsungsem.com/mlcc/CL10A226MO7JZN.do"
			(at 212.09 170.18 0)
			(effects
				(font
					(size 1.27 1.27)
					(thickness 0.15)
				)
				(justify left bottom)
				(hide yes)
			)
		)
		(property "Description" "SMD Multilayer Ceramic Capacitor"
			(at 227.33 190.5 0)
			(effects
				(font
					(size 1.27 1.27)
				)
				(hide yes)
			)
		)
		(property "MPN" "CL10A226MO7JZNC"
			(at 209.55 170.18 0)
			(effects
				(font
					(size 1.27 1.27)
					(thickness 0.15)
				)
				(justify left bottom)
				(hide yes)
			)
		)
		(property "Manufacturer" "Samsung Electro-Mechanics"
			(at 207.01 170.18 0)
			(effects
				(font
					(size 1.27 1.27)
					(thickness 0.15)
				)
				(justify left bottom)
				(hide yes)
			)
		)
		(property "License" "Apache-2.0"
			(at 204.47 170.18 0)
			(effects
				(font
					(size 1.27 1.27)
					(thickness 0.15)
				)
				(justify left bottom)
				(hide yes)
			)
		)
		(property "Author" "Antmicro"
			(at 201.93 170.18 0)
			(effects
				(font
					(size 1.27 1.27)
					(thickness 0.15)
				)
				(justify left bottom)
				(hide yes)
			)
		)
		(property "Val" "22u"
			(at 225.552 189.23 90)
			(effects
				(font
					(size 1.27 1.27)
					(thickness 0.15)
				)
				(justify right)
			)
		)
		(property "Voltage" "16V"
			(at 224.79 190.4935 90)
			(effects
				(font
					(size 1.27 1.27)
				)
				(justify right)
				(hide yes)
			)
		)
		(property "Dielectric" ""
			(at 196.85 170.18 0)
			(effects
				(font
					(size 1.27 1.27)
				)
				(justify left bottom)
				(hide yes)
			)
		)
		(pin "2"
		)
		(pin "1"
		)
		(instances
			(project "thunderbolt-to-10gbe-adapter"
				(path ""
					(reference "C113")
					(unit 1)
				)
			)
		)
	)
	(symbol
		(lib_id "antmicroResistors0402:R_100k_0402")
		(at 256.54 152.4 270)
		(mirror x)
		(unit 1)
		(exclude_from_sim no)
		(in_bom yes)
		(on_board yes)
		(dnp no)
		(property "Reference" "R90"
			(at 255.27 148.59 90)
			(effects
				(font
					(size 1.27 1.27)
					(thickness 0.15)
				)
				(justify right)
			)
		)
		(property "Value" "R_100k_0402"
			(at 243.84 132.08 0)
			(effects
				(font
					(size 1.27 1.27)
					(thickness 0.15)
				)
				(justify left bottom)
				(hide yes)
			)
		)
		(property "Footprint" "antmicro-footprints:R_0402_1005Metric"
			(at 241.3 132.08 0)
			(effects
				(font
					(size 1.27 1.27)
					(thickness 0.15)
				)
				(justify left bottom)
				(hide yes)
			)
		)
		(property "Datasheet" "https://www.bourns.com/docs/product-datasheets/cr.pdf"
			(at 238.76 132.08 0)
			(effects
				(font
					(size 1.27 1.27)
					(thickness 0.15)
				)
				(justify left bottom)
				(hide yes)
			)
		)
		(property "Description" "SMD Chip Resistor, 100 kohm, ± 1%, 62.5 mW, 0402 [1005 Metric], Thick Film, General Purpose"
			(at 226.06 132.08 0)
			(effects
				(font
					(size 1.27 1.27)
				)
				(justify left bottom)
				(hide yes)
			)
		)
		(property "MPN" "CR0402-FX-1003GLF"
			(at 236.22 132.08 0)
			(effects
				(font
					(size 1.27 1.27)
					(thickness 0.15)
				)
				(justify left bottom)
				(hide yes)
			)
		)
		(property "Manufacturer" "Bourns"
			(at 233.68 132.08 0)
			(effects
				(font
					(size 1.27 1.27)
					(thickness 0.15)
				)
				(justify left bottom)
				(hide yes)
			)
		)
		(property "License" "Apache-2.0"
			(at 231.14 132.08 0)
			(effects
				(font
					(size 1.27 1.27)
					(thickness 0.15)
				)
				(justify left bottom)
				(hide yes)
			)
		)
		(property "Author" "Antmicro"
			(at 228.6 132.08 0)
			(effects
				(font
					(size 1.27 1.27)
					(thickness 0.15)
				)
				(justify left bottom)
				(hide yes)
			)
		)
		(property "Val" "100k"
			(at 255.27 151.13 90)
			(effects
				(font
					(size 1.27 1.27)
					(thickness 0.15)
				)
				(justify right)
			)
		)
		(property "Tolerance" "1%"
			(at 246.38 132.08 0)
			(effects
				(font
					(size 1.27 1.27)
				)
				(justify left bottom)
				(hide yes)
			)
		)
		(pin "1"
		)
		(pin "2"
		)
		(instances
			(project "thunderbolt-to-10gbe-adapter"
				(path ""
					(reference "R90")
					(unit 1)
				)
			)
		)
	)
	(symbol
		(lib_id "antmicropower:GND")
		(at 344.17 195.58 0)
		(unit 1)
		(exclude_from_sim no)
		(in_bom yes)
		(on_board yes)
		(dnp no)
		(property "Reference" "#PWR0192"
			(at 353.06 198.12 0)
			(effects
				(font
					(size 1.27 1.27)
					(thickness 0.15)
				)
				(justify left bottom)
				(hide yes)
			)
		)
		(property "Value" "GND"
			(at 344.17 199.39 0)
			(effects
				(font
					(size 1.27 1.27)
					(thickness 0.15)
				)
			)
		)
		(property "Footprint" ""
			(at 353.06 203.2 0)
			(effects
				(font
					(size 1.27 1.27)
					(thickness 0.15)
				)
				(justify left bottom)
				(hide yes)
			)
		)
		(property "Datasheet" ""
			(at 353.06 208.28 0)
			(effects
				(font
					(size 1.27 1.27)
					(thickness 0.15)
				)
				(justify left bottom)
				(hide yes)
			)
		)
		(property "Description" ""
			(at 344.17 195.58 0)
			(effects
				(font
					(size 1.27 1.27)
				)
				(hide yes)
			)
		)
		(property "Author" "Antmicro"
			(at 353.06 203.2 0)
			(effects
				(font
					(size 1.27 1.27)
					(thickness 0.15)
				)
				(justify left bottom)
				(hide yes)
			)
		)
		(property "License" "Apache-2.0"
			(at 353.06 205.74 0)
			(effects
				(font
					(size 1.27 1.27)
					(thickness 0.15)
				)
				(justify left bottom)
				(hide yes)
			)
		)
		(pin "1"
		)
		(instances
			(project "thunderbolt-to-10gbe-adapter"
				(path ""
					(reference "#PWR0192")
					(unit 1)
				)
			)
		)
	)
	(symbol
		(lib_id "antmicroResistors0402:R_63k4_0402")
		(at 332.74 109.22 90)
		(unit 1)
		(exclude_from_sim no)
		(in_bom yes)
		(on_board yes)
		(dnp no)
		(property "Reference" "R102"
			(at 334.01 105.41 90)
			(effects
				(font
					(size 1.27 1.27)
					(thickness 0.15)
				)
				(justify right)
			)
		)
		(property "Value" "R_63k4_0402"
			(at 345.44 88.9 0)
			(effects
				(font
					(size 1.27 1.27)
					(thickness 0.15)
				)
				(justify left bottom)
				(hide yes)
			)
		)
		(property "Footprint" "antmicro-footprints:R_0402_1005Metric"
			(at 347.98 88.9 0)
			(effects
				(font
					(size 1.27 1.27)
					(thickness 0.15)
				)
				(justify left bottom)
				(hide yes)
			)
		)
		(property "Datasheet" "https://industrial.panasonic.com/cdbs/www-data/pdf/RDM0000/AOA0000C307.pdf"
			(at 350.52 88.9 0)
			(effects
				(font
					(size 1.27 1.27)
					(thickness 0.15)
				)
				(justify left bottom)
				(hide yes)
			)
		)
		(property "Description" "SMD Chip Resistor, 63.4 kohm, ± 0.1%, 63 mW, 0402 [1005 Metric], Thin Film,  Precision"
			(at 363.22 88.9 0)
			(effects
				(font
					(size 1.27 1.27)
				)
				(justify left bottom)
				(hide yes)
			)
		)
		(property "MPN" "ERA-2AEB6342X"
			(at 353.06 88.9 0)
			(effects
				(font
					(size 1.27 1.27)
					(thickness 0.15)
				)
				(justify left bottom)
				(hide yes)
			)
		)
		(property "Manufacturer" "Panasonic"
			(at 355.6 88.9 0)
			(effects
				(font
					(size 1.27 1.27)
					(thickness 0.15)
				)
				(justify left bottom)
				(hide yes)
			)
		)
		(property "License" "Apache-2.0"
			(at 358.14 88.9 0)
			(effects
				(font
					(size 1.27 1.27)
					(thickness 0.15)
				)
				(justify left bottom)
				(hide yes)
			)
		)
		(property "Author" "Antmicro"
			(at 360.68 88.9 0)
			(effects
				(font
					(size 1.27 1.27)
					(thickness 0.15)
				)
				(justify left bottom)
				(hide yes)
			)
		)
		(property "Val" "63k4"
			(at 334.01 107.95 90)
			(effects
				(font
					(size 1.27 1.27)
					(thickness 0.15)
				)
				(justify right)
			)
		)
		(property "Tolerance" "0.1%"
			(at 342.9 88.9 0)
			(effects
				(font
					(size 1.27 1.27)
				)
				(justify left bottom)
				(hide yes)
			)
		)
		(pin "2"
		)
		(pin "1"
		)
		(instances
			(project "thunderbolt-to-10gbe-adapter"
				(path ""
					(reference "R102")
					(unit 1)
				)
			)
		)
	)
	(symbol
		(lib_id "antmicroResistors0603:R_0R_22.4A_0603")
		(at 379.73 177.8 0)
		(unit 1)
		(exclude_from_sim no)
		(in_bom yes)
		(on_board yes)
		(dnp no)
		(property "Reference" "R112"
			(at 379.73 176.53 0)
			(effects
				(font
					(size 1.27 1.27)
					(thickness 0.15)
				)
				(justify right)
			)
		)
		(property "Value" "R_0R_22.4A_0603"
			(at 394.97 182.88 0)
			(effects
				(font
					(size 1.27 1.27)
					(thickness 0.15)
				)
				(justify left bottom)
				(hide yes)
			)
		)
		(property "Footprint" "antmicro-footprints:R_0603_1608Metric"
			(at 394.97 187.96 0)
			(effects
				(font
					(size 1.27 1.27)
					(thickness 0.15)
				)
				(justify left bottom)
				(hide yes)
			)
		)
		(property "Datasheet" "https://fscdn.rohm.com/en/products/databook/datasheet/passive/resistor/chip_resistor/pmr-jpw-e.pdf"
			(at 394.97 190.5 0)
			(effects
				(font
					(size 1.27 1.27)
					(thickness 0.15)
				)
				(justify left bottom)
				(hide yes)
			)
		)
		(property "Description" "SMD Chip Resistor"
			(at 394.97 205.74 0)
			(effects
				(font
					(size 1.27 1.27)
				)
				(justify left bottom)
				(hide yes)
			)
		)
		(property "MPN" "PMR03EZPJ000"
			(at 394.97 193.04 0)
			(effects
				(font
					(size 1.27 1.27)
					(thickness 0.15)
				)
				(justify left bottom)
				(hide yes)
			)
		)
		(property "Manufacturer" "ROHM Semiconductor"
			(at 394.97 195.58 0)
			(effects
				(font
					(size 1.27 1.27)
					(thickness 0.15)
				)
				(justify left bottom)
				(hide yes)
			)
		)
		(property "Val" "0R"
			(at 384.81 176.53 0)
			(effects
				(font
					(size 1.27 1.27)
					(thickness 0.15)
				)
				(justify left)
			)
		)
		(property "Max. Curr." "22.4A"
			(at 382.27 180.34 0)
			(effects
				(font
					(size 1.27 1.27)
					(thickness 0.15)
				)
			)
		)
		(property "Author" "Antmicro"
			(at 394.97 200.66 0)
			(effects
				(font
					(size 1.27 1.27)
					(thickness 0.15)
				)
				(justify left bottom)
				(hide yes)
			)
		)
		(property "License" "Apache-2.0"
			(at 394.97 203.2 0)
			(effects
				(font
					(size 1.27 1.27)
					(thickness 0.15)
				)
				(justify left bottom)
				(hide yes)
			)
		)
		(property "Tolerance" "template_tolerance"
			(at 400.05 187.96 0)
			(effects
				(font
					(size 1.27 1.27)
				)
				(justify left bottom)
				(hide yes)
			)
		)
		(pin "1"
		)
		(pin "2"
		)
		(instances
			(project "thunderbolt-to-10gbe-adapter"
				(path ""
					(reference "R112")
					(unit 1)
				)
			)
		)
	)
	(symbol
		(lib_id "antmicropower:PWR_FLAG")
		(at 391.16 22.86 0)
		(unit 1)
		(exclude_from_sim no)
		(in_bom yes)
		(on_board yes)
		(dnp no)
		(property "Reference" "#FLG019"
			(at 391.16 20.955 0)
			(effects
				(font
					(size 1.27 1.27)
				)
				(hide yes)
			)
		)
		(property "Value" "PWR_FLAG"
			(at 391.16 19.05 0)
			(effects
				(font
					(size 1.27 1.27)
				)
			)
		)
		(property "Footprint" ""
			(at 391.16 22.86 0)
			(effects
				(font
					(size 1.27 1.27)
				)
				(hide yes)
			)
		)
		(property "Datasheet" ""
			(at 391.16 22.86 0)
			(effects
				(font
					(size 1.27 1.27)
				)
				(hide yes)
			)
		)
		(property "Description" ""
			(at 391.16 22.86 0)
			(effects
				(font
					(size 1.27 1.27)
				)
				(hide yes)
			)
		)
		(pin "1"
		)
		(instances
			(project "thunderbolt-to-10gbe-adapter"
				(path ""
					(reference "#FLG019")
					(unit 1)
				)
			)
		)
	)
	(symbol
		(lib_id "antmicroResistors0402:R_90k9_0402")
		(at 332.74 33.02 90)
		(unit 1)
		(exclude_from_sim no)
		(in_bom yes)
		(on_board yes)
		(dnp no)
		(property "Reference" "R98"
			(at 334.01 29.21 90)
			(effects
				(font
					(size 1.27 1.27)
					(thickness 0.15)
				)
				(justify right)
			)
		)
		(property "Value" "R_90k9_0402"
			(at 345.44 12.7 0)
			(effects
				(font
					(size 1.27 1.27)
					(thickness 0.15)
				)
				(justify left bottom)
				(hide yes)
			)
		)
		(property "Footprint" "antmicro-footprints:R_0402_1005Metric"
			(at 347.98 12.7 0)
			(effects
				(font
					(size 1.27 1.27)
					(thickness 0.15)
				)
				(justify left bottom)
				(hide yes)
			)
		)
		(property "Datasheet" "https://www.bourns.com/docs/product-datasheets/cr.pdf"
			(at 350.52 12.7 0)
			(effects
				(font
					(size 1.27 1.27)
					(thickness 0.15)
				)
				(justify left bottom)
				(hide yes)
			)
		)
		(property "Description" "SMD Chip Resistor"
			(at 363.22 12.7 0)
			(effects
				(font
					(size 1.27 1.27)
				)
				(justify left bottom)
				(hide yes)
			)
		)
		(property "MPN" "CR0402-FX-9092GLF"
			(at 353.06 12.7 0)
			(effects
				(font
					(size 1.27 1.27)
					(thickness 0.15)
				)
				(justify left bottom)
				(hide yes)
			)
		)
		(property "Manufacturer" "Bourns"
			(at 355.6 12.7 0)
			(effects
				(font
					(size 1.27 1.27)
					(thickness 0.15)
				)
				(justify left bottom)
				(hide yes)
			)
		)
		(property "License" "Apache-2.0"
			(at 358.14 12.7 0)
			(effects
				(font
					(size 1.27 1.27)
					(thickness 0.15)
				)
				(justify left bottom)
				(hide yes)
			)
		)
		(property "Author" "Antmicro"
			(at 360.68 12.7 0)
			(effects
				(font
					(size 1.27 1.27)
					(thickness 0.15)
				)
				(justify left bottom)
				(hide yes)
			)
		)
		(property "Val" "90k9"
			(at 334.01 31.75 90)
			(effects
				(font
					(size 1.27 1.27)
					(thickness 0.15)
				)
				(justify right)
			)
		)
		(property "Tolerance" "1%"
			(at 342.9 12.7 0)
			(effects
				(font
					(size 1.27 1.27)
				)
				(justify left bottom)
				(hide yes)
			)
		)
		(pin "1"
		)
		(pin "2"
		)
		(instances
			(project "thunderbolt-to-10gbe-adapter"
				(path ""
					(reference "R98")
					(unit 1)
				)
			)
		)
	)
	(symbol
		(lib_id "antmicropower:+3V3")
		(at 400.05 22.86 0)
		(unit 1)
		(exclude_from_sim no)
		(in_bom yes)
		(on_board yes)
		(dnp no)
		(property "Reference" "#PWR0213"
			(at 415.29 22.86 0)
			(effects
				(font
					(size 1.27 1.27)
					(thickness 0.15)
				)
				(justify left bottom)
				(hide yes)
			)
		)
		(property "Value" "+3V3"
			(at 400.05 19.05 0)
			(effects
				(font
					(size 1.27 1.27)
					(thickness 0.15)
				)
			)
		)
		(property "Footprint" ""
			(at 415.29 30.48 0)
			(effects
				(font
					(size 1.27 1.27)
					(thickness 0.15)
				)
				(justify left bottom)
				(hide yes)
			)
		)
		(property "Datasheet" ""
			(at 415.29 33.02 0)
			(effects
				(font
					(size 1.27 1.27)
					(thickness 0.15)
				)
				(justify left bottom)
				(hide yes)
			)
		)
		(property "Description" ""
			(at 400.05 22.86 0)
			(effects
				(font
					(size 1.27 1.27)
				)
				(hide yes)
			)
		)
		(property "Author" "Antmicro"
			(at 415.29 25.4 0)
			(effects
				(font
					(size 1.27 1.27)
					(thickness 0.15)
				)
				(justify left bottom)
				(hide yes)
			)
		)
		(property "License" "Apache-2.0"
			(at 415.29 27.94 0)
			(effects
				(font
					(size 1.27 1.27)
					(thickness 0.15)
				)
				(justify left bottom)
				(hide yes)
			)
		)
		(pin "1"
		)
		(instances
			(project "thunderbolt-to-10gbe-adapter"
				(path ""
					(reference "#PWR0213")
					(unit 1)
				)
			)
		)
	)
	(symbol
		(lib_id "antmicropower:GND")
		(at 177.8 246.38 0)
		(mirror y)
		(unit 1)
		(exclude_from_sim no)
		(in_bom yes)
		(on_board yes)
		(dnp no)
		(property "Reference" "#PWR0147"
			(at 168.91 248.92 0)
			(effects
				(font
					(size 1.27 1.27)
					(thickness 0.15)
				)
				(justify left bottom)
				(hide yes)
			)
		)
		(property "Value" "GND"
			(at 177.8 250.19 0)
			(effects
				(font
					(size 1.27 1.27)
					(thickness 0.15)
				)
			)
		)
		(property "Footprint" ""
			(at 168.91 254 0)
			(effects
				(font
					(size 1.27 1.27)
					(thickness 0.15)
				)
				(justify left bottom)
				(hide yes)
			)
		)
		(property "Datasheet" ""
			(at 168.91 259.08 0)
			(effects
				(font
					(size 1.27 1.27)
					(thickness 0.15)
				)
				(justify left bottom)
				(hide yes)
			)
		)
		(property "Description" ""
			(at 177.8 246.38 0)
			(effects
				(font
					(size 1.27 1.27)
				)
				(hide yes)
			)
		)
		(property "Author" "Antmicro"
			(at 168.91 254 0)
			(effects
				(font
					(size 1.27 1.27)
					(thickness 0.15)
				)
				(justify left bottom)
				(hide yes)
			)
		)
		(property "License" "Apache-2.0"
			(at 168.91 256.54 0)
			(effects
				(font
					(size 1.27 1.27)
					(thickness 0.15)
				)
				(justify left bottom)
				(hide yes)
			)
		)
		(pin "1"
		)
		(instances
			(project "thunderbolt-to-10gbe-adapter"
				(path ""
					(reference "#PWR0147")
					(unit 1)
				)
			)
		)
	)
	(symbol
		(lib_id "antmicroResistors0402:R_20k_0402")
		(at 332.74 41.91 90)
		(unit 1)
		(exclude_from_sim no)
		(in_bom yes)
		(on_board yes)
		(dnp no)
		(property "Reference" "R99"
			(at 334.01 38.1 90)
			(effects
				(font
					(size 1.27 1.27)
					(thickness 0.15)
				)
				(justify right)
			)
		)
		(property "Value" "R_20k_0402"
			(at 345.44 21.59 0)
			(effects
				(font
					(size 1.27 1.27)
					(thickness 0.15)
				)
				(justify left bottom)
				(hide yes)
			)
		)
		(property "Footprint" "antmicro-footprints:R_0402_1005Metric"
			(at 347.98 21.59 0)
			(effects
				(font
					(size 1.27 1.27)
					(thickness 0.15)
				)
				(justify left bottom)
				(hide yes)
			)
		)
		(property "Datasheet" "https://www.bourns.com/docs/product-datasheets/cr.pdf"
			(at 350.52 21.59 0)
			(effects
				(font
					(size 1.27 1.27)
					(thickness 0.15)
				)
				(justify left bottom)
				(hide yes)
			)
		)
		(property "Description" "SMD Chip Resistor, 20 kohm, ± 1%, 62.5 mW, 0402 [1005 Metric], Thick Film, General Purpose"
			(at 363.22 21.59 0)
			(effects
				(font
					(size 1.27 1.27)
				)
				(justify left bottom)
				(hide yes)
			)
		)
		(property "MPN" "CR0402-FX-2002GLF"
			(at 353.06 21.59 0)
			(effects
				(font
					(size 1.27 1.27)
					(thickness 0.15)
				)
				(justify left bottom)
				(hide yes)
			)
		)
		(property "Manufacturer" "Bourns"
			(at 355.6 21.59 0)
			(effects
				(font
					(size 1.27 1.27)
					(thickness 0.15)
				)
				(justify left bottom)
				(hide yes)
			)
		)
		(property "License" "Apache-2.0"
			(at 358.14 21.59 0)
			(effects
				(font
					(size 1.27 1.27)
					(thickness 0.15)
				)
				(justify left bottom)
				(hide yes)
			)
		)
		(property "Author" "Antmicro"
			(at 360.68 21.59 0)
			(effects
				(font
					(size 1.27 1.27)
					(thickness 0.15)
				)
				(justify left bottom)
				(hide yes)
			)
		)
		(property "Val" "20k"
			(at 334.01 40.64 90)
			(effects
				(font
					(size 1.27 1.27)
					(thickness 0.15)
				)
				(justify right)
			)
		)
		(property "Tolerance" "1%"
			(at 342.9 21.59 0)
			(effects
				(font
					(size 1.27 1.27)
				)
				(justify left bottom)
				(hide yes)
			)
		)
		(pin "2"
		)
		(pin "1"
		)
		(instances
			(project "thunderbolt-to-10gbe-adapter"
				(path ""
					(reference "R99")
					(unit 1)
				)
			)
		)
	)
	(symbol
		(lib_id "antmicroCapacitors0603:C_22u_16V_0603")
		(at 344.17 114.3 90)
		(unit 1)
		(exclude_from_sim no)
		(in_bom yes)
		(on_board yes)
		(dnp no)
		(property "Reference" "C136"
			(at 346.202 110.49 90)
			(effects
				(font
					(size 1.27 1.27)
					(thickness 0.15)
				)
				(justify right)
			)
		)
		(property "Value" "C_22u_16V_0603"
			(at 354.33 93.98 0)
			(effects
				(font
					(size 1.27 1.27)
					(thickness 0.15)
				)
				(justify left bottom)
				(hide yes)
			)
		)
		(property "Footprint" "antmicro-footprints:C_0603_1608Metric_EIA"
			(at 356.87 93.98 0)
			(effects
				(font
					(size 1.27 1.27)
					(thickness 0.15)
				)
				(justify left bottom)
				(hide yes)
			)
		)
		(property "Datasheet" "https://product.samsungsem.com/mlcc/CL10A226MO7JZN.do"
			(at 359.41 93.98 0)
			(effects
				(font
					(size 1.27 1.27)
					(thickness 0.15)
				)
				(justify left bottom)
				(hide yes)
			)
		)
		(property "Description" "SMD Multilayer Ceramic Capacitor"
			(at 344.17 114.3 0)
			(effects
				(font
					(size 1.27 1.27)
				)
				(hide yes)
			)
		)
		(property "MPN" "CL10A226MO7JZNC"
			(at 361.95 93.98 0)
			(effects
				(font
					(size 1.27 1.27)
					(thickness 0.15)
				)
				(justify left bottom)
				(hide yes)
			)
		)
		(property "Manufacturer" "Samsung Electro-Mechanics"
			(at 364.49 93.98 0)
			(effects
				(font
					(size 1.27 1.27)
					(thickness 0.15)
				)
				(justify left bottom)
				(hide yes)
			)
		)
		(property "License" "Apache-2.0"
			(at 367.03 93.98 0)
			(effects
				(font
					(size 1.27 1.27)
					(thickness 0.15)
				)
				(justify left bottom)
				(hide yes)
			)
		)
		(property "Author" "Antmicro"
			(at 369.57 93.98 0)
			(effects
				(font
					(size 1.27 1.27)
					(thickness 0.15)
				)
				(justify left bottom)
				(hide yes)
			)
		)
		(property "Val" "22u"
			(at 346.202 113.03 90)
			(effects
				(font
					(size 1.27 1.27)
					(thickness 0.15)
				)
				(justify right)
			)
		)
		(property "Voltage" "16V"
			(at 346.71 114.2935 90)
			(effects
				(font
					(size 1.27 1.27)
				)
				(justify right)
				(hide yes)
			)
		)
		(property "Dielectric" ""
			(at 374.65 93.98 0)
			(effects
				(font
					(size 1.27 1.27)
				)
				(justify left bottom)
				(hide yes)
			)
		)
		(pin "2"
		)
		(pin "1"
		)
		(instances
			(project "thunderbolt-to-10gbe-adapter"
				(path ""
					(reference "C136")
					(unit 1)
				)
			)
		)
	)
	(symbol
		(lib_id "antmicroResistors0402:R_0R_0402")
		(at 261.62 149.86 0)
		(unit 1)
		(exclude_from_sim no)
		(in_bom yes)
		(on_board yes)
		(dnp no)
		(property "Reference" "R94"
			(at 264.16 147.574 0)
			(effects
				(font
					(size 1.27 1.27)
					(thickness 0.15)
				)
			)
		)
		(property "Value" "R_0R_0402"
			(at 281.94 162.56 0)
			(effects
				(font
					(size 1.27 1.27)
					(thickness 0.15)
				)
				(justify left bottom)
				(hide yes)
			)
		)
		(property "Footprint" "antmicro-footprints:R_0402_1005Metric"
			(at 281.94 165.1 0)
			(effects
				(font
					(size 1.27 1.27)
					(thickness 0.15)
				)
				(justify left bottom)
				(hide yes)
			)
		)
		(property "Datasheet" "https://industrial.panasonic.com/cdbs/www-data/pdf/RDA0000/AOA0000C301.pdf"
			(at 281.94 167.64 0)
			(effects
				(font
					(size 1.27 1.27)
					(thickness 0.15)
				)
				(justify left bottom)
				(hide yes)
			)
		)
		(property "Description" "SMD Chip Resistor, Jumper, 0 ohm, 100 mW, 0402 [1005 Metric], Thick Film, General Purpose"
			(at 281.94 182.88 0)
			(effects
				(font
					(size 1.27 1.27)
				)
				(justify left bottom)
				(hide yes)
			)
		)
		(property "MPN" "ERJ2GE0R00X"
			(at 281.94 170.18 0)
			(effects
				(font
					(size 1.27 1.27)
					(thickness 0.15)
				)
				(justify left bottom)
				(hide yes)
			)
		)
		(property "Manufacturer" "Panasonic"
			(at 281.94 172.72 0)
			(effects
				(font
					(size 1.27 1.27)
					(thickness 0.15)
				)
				(justify left bottom)
				(hide yes)
			)
		)
		(property "License" "Apache-2.0"
			(at 281.94 175.26 0)
			(effects
				(font
					(size 1.27 1.27)
					(thickness 0.15)
				)
				(justify left bottom)
				(hide yes)
			)
		)
		(property "Author" "Antmicro"
			(at 281.94 177.8 0)
			(effects
				(font
					(size 1.27 1.27)
					(thickness 0.15)
				)
				(justify left bottom)
				(hide yes)
			)
		)
		(property "Val" "0R"
			(at 264.16 152.146 0)
			(effects
				(font
					(size 1.27 1.27)
					(thickness 0.15)
				)
			)
		)
		(property "Tolerance" "~"
			(at 281.94 160.02 0)
			(effects
				(font
					(size 1.27 1.27)
				)
				(justify left bottom)
				(hide yes)
			)
		)
		(property "Current" "1A"
			(at 281.94 180.34 0)
			(effects
				(font
					(size 1.27 1.27)
					(thickness 0.15)
				)
				(justify left bottom)
				(hide yes)
			)
		)
		(pin "2"
		)
		(pin "1"
		)
		(instances
			(project "thunderbolt-to-10gbe-adapter"
				(path ""
					(reference "R94")
					(unit 1)
				)
			)
		)
	)
	(symbol
		(lib_id "antmicroCapacitors0603:C_22u_16V_0603")
		(at 217.17 190.5 270)
		(mirror x)
		(unit 1)
		(exclude_from_sim no)
		(in_bom yes)
		(on_board yes)
		(dnp no)
		(property "Reference" "C108"
			(at 215.138 186.69 90)
			(effects
				(font
					(size 1.27 1.27)
					(thickness 0.15)
				)
				(justify right)
			)
		)
		(property "Value" "C_22u_16V_0603"
			(at 207.01 170.18 0)
			(effects
				(font
					(size 1.27 1.27)
					(thickness 0.15)
				)
				(justify left bottom)
				(hide yes)
			)
		)
		(property "Footprint" "antmicro-footprints:C_0603_1608Metric_EIA"
			(at 204.47 170.18 0)
			(effects
				(font
					(size 1.27 1.27)
					(thickness 0.15)
				)
				(justify left bottom)
				(hide yes)
			)
		)
		(property "Datasheet" "https://product.samsungsem.com/mlcc/CL10A226MO7JZN.do"
			(at 201.93 170.18 0)
			(effects
				(font
					(size 1.27 1.27)
					(thickness 0.15)
				)
				(justify left bottom)
				(hide yes)
			)
		)
		(property "Description" "SMD Multilayer Ceramic Capacitor"
			(at 217.17 190.5 0)
			(effects
				(font
					(size 1.27 1.27)
				)
				(hide yes)
			)
		)
		(property "MPN" "CL10A226MO7JZNC"
			(at 199.39 170.18 0)
			(effects
				(font
					(size 1.27 1.27)
					(thickness 0.15)
				)
				(justify left bottom)
				(hide yes)
			)
		)
		(property "Manufacturer" "Samsung Electro-Mechanics"
			(at 196.85 170.18 0)
			(effects
				(font
					(size 1.27 1.27)
					(thickness 0.15)
				)
				(justify left bottom)
				(hide yes)
			)
		)
		(property "License" "Apache-2.0"
			(at 194.31 170.18 0)
			(effects
				(font
					(size 1.27 1.27)
					(thickness 0.15)
				)
				(justify left bottom)
				(hide yes)
			)
		)
		(property "Author" "Antmicro"
			(at 191.77 170.18 0)
			(effects
				(font
					(size 1.27 1.27)
					(thickness 0.15)
				)
				(justify left bottom)
				(hide yes)
			)
		)
		(property "Val" "22u"
			(at 215.138 189.23 90)
			(effects
				(font
					(size 1.27 1.27)
					(thickness 0.15)
				)
				(justify right)
			)
		)
		(property "Voltage" "16V"
			(at 214.63 190.4935 90)
			(effects
				(font
					(size 1.27 1.27)
				)
				(justify right)
				(hide yes)
			)
		)
		(property "Dielectric" ""
			(at 186.69 170.18 0)
			(effects
				(font
					(size 1.27 1.27)
				)
				(justify left bottom)
				(hide yes)
			)
		)
		(pin "2"
		)
		(pin "1"
		)
		(instances
			(project "thunderbolt-to-10gbe-adapter"
				(path ""
					(reference "C108")
					(unit 1)
				)
			)
		)
	)
	(symbol
		(lib_id "antmicroTestPoints:TP_0.75mm_SMD")
		(at 391.16 231.14 0)
		(unit 1)
		(exclude_from_sim no)
		(in_bom no)
		(on_board yes)
		(dnp no)
		(fields_autoplaced yes)
		(property "Reference" "TP16"
			(at 396.24 231.14 0)
			(effects
				(font
					(size 1.27 1.27)
					(thickness 0.15)
				)
				(justify left)
			)
		)
		(property "Value" "TP_0.75mm_SMD"
			(at 401.32 234.95 0)
			(effects
				(font
					(size 1.27 1.27)
					(thickness 0.15)
				)
				(justify left bottom)
				(hide yes)
			)
		)
		(property "Footprint" "antmicro-footprints:TP_SMD_0.75mm"
			(at 401.32 237.49 0)
			(effects
				(font
					(size 1.27 1.27)
					(thickness 0.15)
				)
				(justify left bottom)
				(hide yes)
			)
		)
		(property "Datasheet" ""
			(at 408.94 243.84 0)
			(effects
				(font
					(size 1.27 1.27)
					(thickness 0.15)
				)
				(justify left bottom)
				(hide yes)
			)
		)
		(property "Description" "SMT test point"
			(at 401.955 245.11 0)
			(effects
				(font
					(size 1.27 1.27)
				)
				(justify left bottom)
				(hide yes)
			)
		)
		(property "MPN" ""
			(at 401.955 242.57 0)
			(effects
				(font
					(size 1.27 1.27)
					(thickness 0.15)
				)
				(justify left bottom)
				(hide yes)
			)
		)
		(property "Manufacturer" ""
			(at 401.955 237.49 0)
			(effects
				(font
					(size 1.27 1.27)
					(thickness 0.15)
				)
				(justify left bottom)
				(hide yes)
			)
		)
		(property "Author" "Antmicro"
			(at 401.32 240.03 0)
			(effects
				(font
					(size 1.27 1.27)
					(thickness 0.15)
				)
				(justify left bottom)
				(hide yes)
			)
		)
		(property "License" "Apache-2.0"
			(at 401.32 242.57 0)
			(effects
				(font
					(size 1.27 1.27)
					(thickness 0.15)
				)
				(justify left bottom)
				(hide yes)
			)
		)
		(pin "1"
		)
		(instances
			(project "thunderbolt-to-10gbe-adapter"
				(path ""
					(reference "TP16")
					(unit 1)
				)
			)
		)
	)
	(symbol
		(lib_id "antmicroResistors0603:R_0R_22.4A_0603")
		(at 379.73 139.7 0)
		(unit 1)
		(exclude_from_sim no)
		(in_bom yes)
		(on_board yes)
		(dnp no)
		(property "Reference" "R111"
			(at 379.73 138.43 0)
			(effects
				(font
					(size 1.27 1.27)
					(thickness 0.15)
				)
				(justify right)
			)
		)
		(property "Value" "R_0R_22.4A_0603"
			(at 394.97 144.78 0)
			(effects
				(font
					(size 1.27 1.27)
					(thickness 0.15)
				)
				(justify left bottom)
				(hide yes)
			)
		)
		(property "Footprint" "antmicro-footprints:R_0603_1608Metric"
			(at 394.97 149.86 0)
			(effects
				(font
					(size 1.27 1.27)
					(thickness 0.15)
				)
				(justify left bottom)
				(hide yes)
			)
		)
		(property "Datasheet" "https://fscdn.rohm.com/en/products/databook/datasheet/passive/resistor/chip_resistor/pmr-jpw-e.pdf"
			(at 394.97 152.4 0)
			(effects
				(font
					(size 1.27 1.27)
					(thickness 0.15)
				)
				(justify left bottom)
				(hide yes)
			)
		)
		(property "Description" "SMD Chip Resistor"
			(at 394.97 167.64 0)
			(effects
				(font
					(size 1.27 1.27)
				)
				(justify left bottom)
				(hide yes)
			)
		)
		(property "MPN" "PMR03EZPJ000"
			(at 394.97 154.94 0)
			(effects
				(font
					(size 1.27 1.27)
					(thickness 0.15)
				)
				(justify left bottom)
				(hide yes)
			)
		)
		(property "Manufacturer" "ROHM Semiconductor"
			(at 394.97 157.48 0)
			(effects
				(font
					(size 1.27 1.27)
					(thickness 0.15)
				)
				(justify left bottom)
				(hide yes)
			)
		)
		(property "Val" "0R"
			(at 384.81 138.43 0)
			(effects
				(font
					(size 1.27 1.27)
					(thickness 0.15)
				)
				(justify left)
			)
		)
		(property "Max. Curr." "22.4A"
			(at 382.27 142.24 0)
			(effects
				(font
					(size 1.27 1.27)
					(thickness 0.15)
				)
			)
		)
		(property "Author" "Antmicro"
			(at 394.97 162.56 0)
			(effects
				(font
					(size 1.27 1.27)
					(thickness 0.15)
				)
				(justify left bottom)
				(hide yes)
			)
		)
		(property "License" "Apache-2.0"
			(at 394.97 165.1 0)
			(effects
				(font
					(size 1.27 1.27)
					(thickness 0.15)
				)
				(justify left bottom)
				(hide yes)
			)
		)
		(property "Tolerance" "template_tolerance"
			(at 400.05 149.86 0)
			(effects
				(font
					(size 1.27 1.27)
				)
				(justify left bottom)
				(hide yes)
			)
		)
		(pin "1"
		)
		(pin "2"
		)
		(instances
			(project "thunderbolt-to-10gbe-adapter"
				(path ""
					(reference "R111")
					(unit 1)
				)
			)
		)
	)
	(symbol
		(lib_id "antmicropower:GND")
		(at 247.65 119.38 0)
		(unit 1)
		(exclude_from_sim no)
		(in_bom yes)
		(on_board yes)
		(dnp no)
		(property "Reference" "#PWR0172"
			(at 256.54 121.92 0)
			(effects
				(font
					(size 1.27 1.27)
					(thickness 0.15)
				)
				(justify left bottom)
				(hide yes)
			)
		)
		(property "Value" "GND"
			(at 247.65 123.19 0)
			(effects
				(font
					(size 1.27 1.27)
					(thickness 0.15)
				)
			)
		)
		(property "Footprint" ""
			(at 256.54 127 0)
			(effects
				(font
					(size 1.27 1.27)
					(thickness 0.15)
				)
				(justify left bottom)
				(hide yes)
			)
		)
		(property "Datasheet" ""
			(at 256.54 132.08 0)
			(effects
				(font
					(size 1.27 1.27)
					(thickness 0.15)
				)
				(justify left bottom)
				(hide yes)
			)
		)
		(property "Description" ""
			(at 247.65 119.38 0)
			(effects
				(font
					(size 1.27 1.27)
				)
				(hide yes)
			)
		)
		(property "Author" "Antmicro"
			(at 256.54 127 0)
			(effects
				(font
					(size 1.27 1.27)
					(thickness 0.15)
				)
				(justify left bottom)
				(hide yes)
			)
		)
		(property "License" "Apache-2.0"
			(at 256.54 129.54 0)
			(effects
				(font
					(size 1.27 1.27)
					(thickness 0.15)
				)
				(justify left bottom)
				(hide yes)
			)
		)
		(pin "1"
		)
		(instances
			(project "thunderbolt-to-10gbe-adapter"
				(path ""
					(reference "#PWR0172")
					(unit 1)
				)
			)
		)
	)
	(symbol
		(lib_id "antmicropower:GND")
		(at 227.33 43.18 0)
		(unit 1)
		(exclude_from_sim no)
		(in_bom yes)
		(on_board yes)
		(dnp no)
		(property "Reference" "#PWR0159"
			(at 236.22 45.72 0)
			(effects
				(font
					(size 1.27 1.27)
					(thickness 0.15)
				)
				(justify left bottom)
				(hide yes)
			)
		)
		(property "Value" "GND"
			(at 227.33 46.99 0)
			(effects
				(font
					(size 1.27 1.27)
					(thickness 0.15)
				)
			)
		)
		(property "Footprint" ""
			(at 236.22 50.8 0)
			(effects
				(font
					(size 1.27 1.27)
					(thickness 0.15)
				)
				(justify left bottom)
				(hide yes)
			)
		)
		(property "Datasheet" ""
			(at 236.22 55.88 0)
			(effects
				(font
					(size 1.27 1.27)
					(thickness 0.15)
				)
				(justify left bottom)
				(hide yes)
			)
		)
		(property "Description" ""
			(at 227.33 43.18 0)
			(effects
				(font
					(size 1.27 1.27)
				)
				(hide yes)
			)
		)
		(property "Author" "Antmicro"
			(at 236.22 50.8 0)
			(effects
				(font
					(size 1.27 1.27)
					(thickness 0.15)
				)
				(justify left bottom)
				(hide yes)
			)
		)
		(property "License" "Apache-2.0"
			(at 236.22 53.34 0)
			(effects
				(font
					(size 1.27 1.27)
					(thickness 0.15)
				)
				(justify left bottom)
				(hide yes)
			)
		)
		(pin "1"
		)
		(instances
			(project "thunderbolt-to-10gbe-adapter"
				(path ""
					(reference "#PWR0159")
					(unit 1)
				)
			)
		)
	)
	(symbol
		(lib_id "antmicropower:GND")
		(at 388.62 242.57 0)
		(unit 1)
		(exclude_from_sim no)
		(in_bom yes)
		(on_board yes)
		(dnp no)
		(property "Reference" "#PWR0451"
			(at 397.51 245.11 0)
			(effects
				(font
					(size 1.27 1.27)
					(thickness 0.15)
				)
				(justify left bottom)
				(hide yes)
			)
		)
		(property "Value" "GND"
			(at 388.62 246.38 0)
			(effects
				(font
					(size 1.27 1.27)
					(thickness 0.15)
				)
			)
		)
		(property "Footprint" ""
			(at 397.51 250.19 0)
			(effects
				(font
					(size 1.27 1.27)
					(thickness 0.15)
				)
				(justify left bottom)
				(hide yes)
			)
		)
		(property "Datasheet" ""
			(at 397.51 255.27 0)
			(effects
				(font
					(size 1.27 1.27)
					(thickness 0.15)
				)
				(justify left bottom)
				(hide yes)
			)
		)
		(property "Description" ""
			(at 397.51 257.81 0)
			(effects
				(font
					(size 1.27 1.27)
				)
				(justify left bottom)
				(hide yes)
			)
		)
		(property "Author" "Antmicro"
			(at 397.51 250.19 0)
			(effects
				(font
					(size 1.27 1.27)
					(thickness 0.15)
				)
				(justify left bottom)
				(hide yes)
			)
		)
		(property "License" "Apache-2.0"
			(at 397.51 252.73 0)
			(effects
				(font
					(size 1.27 1.27)
					(thickness 0.15)
				)
				(justify left bottom)
				(hide yes)
			)
		)
		(pin "1"
		)
		(instances
			(project "thunderbolt-to-10gbe-adapter"
				(path ""
					(reference "#PWR0451")
					(unit 1)
				)
			)
		)
	)
	(symbol
		(lib_id "antmicroResistors0402:R_330R_0402")
		(at 177.8 231.14 90)
		(unit 1)
		(exclude_from_sim no)
		(in_bom yes)
		(on_board yes)
		(dnp no)
		(property "Reference" "R83"
			(at 179.07 227.33 90)
			(effects
				(font
					(size 1.27 1.27)
					(thickness 0.15)
				)
				(justify right)
			)
		)
		(property "Value" "R_330R_0402"
			(at 190.5 210.82 0)
			(effects
				(font
					(size 1.27 1.27)
					(thickness 0.15)
				)
				(justify left bottom)
				(hide yes)
			)
		)
		(property "Footprint" "antmicro-footprints:R_0402_1005Metric"
			(at 193.04 210.82 0)
			(effects
				(font
					(size 1.27 1.27)
					(thickness 0.15)
				)
				(justify left bottom)
				(hide yes)
			)
		)
		(property "Datasheet" "https://www.bourns.com/docs/product-datasheets/cr.pdf"
			(at 195.58 210.82 0)
			(effects
				(font
					(size 1.27 1.27)
					(thickness 0.15)
				)
				(justify left bottom)
				(hide yes)
			)
		)
		(property "Description" "SMD Chip Resistor, 330 ohm, ± 1%, 62.5 mW, 0402 [1005 Metric], Thick Film, General Purpose"
			(at 208.28 210.82 0)
			(effects
				(font
					(size 1.27 1.27)
				)
				(justify left bottom)
				(hide yes)
			)
		)
		(property "MPN" "CR0402-FX-3300GLF"
			(at 198.12 210.82 0)
			(effects
				(font
					(size 1.27 1.27)
					(thickness 0.15)
				)
				(justify left bottom)
				(hide yes)
			)
		)
		(property "Manufacturer" "Bourns"
			(at 200.66 210.82 0)
			(effects
				(font
					(size 1.27 1.27)
					(thickness 0.15)
				)
				(justify left bottom)
				(hide yes)
			)
		)
		(property "License" "Apache-2.0"
			(at 203.2 210.82 0)
			(effects
				(font
					(size 1.27 1.27)
					(thickness 0.15)
				)
				(justify left bottom)
				(hide yes)
			)
		)
		(property "Author" "Antmicro"
			(at 205.74 210.82 0)
			(effects
				(font
					(size 1.27 1.27)
					(thickness 0.15)
				)
				(justify left bottom)
				(hide yes)
			)
		)
		(property "Val" "330R"
			(at 179.07 229.87 90)
			(effects
				(font
					(size 1.27 1.27)
					(thickness 0.15)
				)
				(justify right)
			)
		)
		(property "Tolerance" "1%"
			(at 187.96 210.82 0)
			(effects
				(font
					(size 1.27 1.27)
				)
				(justify left bottom)
				(hide yes)
			)
		)
		(pin "2"
		)
		(pin "1"
		)
		(instances
			(project "thunderbolt-to-10gbe-adapter"
				(path ""
					(reference "R83")
					(unit 1)
				)
			)
		)
	)
	(symbol
		(lib_id "antmicroCapacitors0402:C_100n_0402")
		(at 237.49 114.3 270)
		(mirror x)
		(unit 1)
		(exclude_from_sim no)
		(in_bom yes)
		(on_board yes)
		(dnp no)
		(property "Reference" "C116"
			(at 235.712 110.49 90)
			(effects
				(font
					(size 1.27 1.27)
					(thickness 0.15)
				)
				(justify right)
			)
		)
		(property "Value" "C_100n_0402"
			(at 227.33 93.98 0)
			(effects
				(font
					(size 1.27 1.27)
					(thickness 0.15)
				)
				(justify left bottom)
				(hide yes)
			)
		)
		(property "Footprint" "antmicro-footprints:C_0402_1005Metric"
			(at 224.79 93.98 0)
			(effects
				(font
					(size 1.27 1.27)
					(thickness 0.15)
				)
				(justify left bottom)
				(hide yes)
			)
		)
		(property "Datasheet" "https://www.murata.com/products/productdetail?partno=GRM155R61H104KE14%23"
			(at 222.25 93.98 0)
			(effects
				(font
					(size 1.27 1.27)
					(thickness 0.15)
				)
				(justify left bottom)
				(hide yes)
			)
		)
		(property "Description" "SMD Multilayer Ceramic Capacitor, 0.1 µF, 50 V, 0402 [1005 Metric], ± 10%, X5R, GRM Series"
			(at 204.47 93.98 0)
			(effects
				(font
					(size 1.27 1.27)
				)
				(justify left bottom)
				(hide yes)
			)
		)
		(property "MPN" "GRM155R61H104KE14D"
			(at 219.71 93.98 0)
			(effects
				(font
					(size 1.27 1.27)
					(thickness 0.15)
				)
				(justify left bottom)
				(hide yes)
			)
		)
		(property "Manufacturer" "Murata"
			(at 217.17 93.98 0)
			(effects
				(font
					(size 1.27 1.27)
					(thickness 0.15)
				)
				(justify left bottom)
				(hide yes)
			)
		)
		(property "License" "Apache-2.0"
			(at 214.63 93.98 0)
			(effects
				(font
					(size 1.27 1.27)
					(thickness 0.15)
				)
				(justify left bottom)
				(hide yes)
			)
		)
		(property "Author" "Antmicro"
			(at 212.09 93.98 0)
			(effects
				(font
					(size 1.27 1.27)
					(thickness 0.15)
				)
				(justify left bottom)
				(hide yes)
			)
		)
		(property "Val" "100n"
			(at 235.712 113.03 90)
			(effects
				(font
					(size 1.27 1.27)
					(thickness 0.15)
				)
				(justify right)
			)
		)
		(property "Voltage" "50V"
			(at 209.55 93.98 0)
			(effects
				(font
					(size 1.27 1.27)
				)
				(justify left bottom)
				(hide yes)
			)
		)
		(property "Dielectric" "X5R"
			(at 207.01 93.98 0)
			(effects
				(font
					(size 1.27 1.27)
				)
				(justify left bottom)
				(hide yes)
			)
		)
		(pin "1"
		)
		(pin "2"
		)
		(instances
			(project "thunderbolt-to-10gbe-adapter"
				(path ""
					(reference "C116")
					(unit 1)
				)
			)
		)
	)
	(symbol
		(lib_id "antmicroCapacitors0603:C_22u_16V_0603")
		(at 354.33 114.3 90)
		(unit 1)
		(exclude_from_sim no)
		(in_bom yes)
		(on_board yes)
		(dnp no)
		(property "Reference" "C141"
			(at 356.108 110.49 90)
			(effects
				(font
					(size 1.27 1.27)
					(thickness 0.15)
				)
				(justify right)
			)
		)
		(property "Value" "C_22u_16V_0603"
			(at 364.49 93.98 0)
			(effects
				(font
					(size 1.27 1.27)
					(thickness 0.15)
				)
				(justify left bottom)
				(hide yes)
			)
		)
		(property "Footprint" "antmicro-footprints:C_0603_1608Metric_EIA"
			(at 367.03 93.98 0)
			(effects
				(font
					(size 1.27 1.27)
					(thickness 0.15)
				)
				(justify left bottom)
				(hide yes)
			)
		)
		(property "Datasheet" "https://product.samsungsem.com/mlcc/CL10A226MO7JZN.do"
			(at 369.57 93.98 0)
			(effects
				(font
					(size 1.27 1.27)
					(thickness 0.15)
				)
				(justify left bottom)
				(hide yes)
			)
		)
		(property "Description" "SMD Multilayer Ceramic Capacitor"
			(at 354.33 114.3 0)
			(effects
				(font
					(size 1.27 1.27)
				)
				(hide yes)
			)
		)
		(property "MPN" "CL10A226MO7JZNC"
			(at 372.11 93.98 0)
			(effects
				(font
					(size 1.27 1.27)
					(thickness 0.15)
				)
				(justify left bottom)
				(hide yes)
			)
		)
		(property "Manufacturer" "Samsung Electro-Mechanics"
			(at 374.65 93.98 0)
			(effects
				(font
					(size 1.27 1.27)
					(thickness 0.15)
				)
				(justify left bottom)
				(hide yes)
			)
		)
		(property "License" "Apache-2.0"
			(at 377.19 93.98 0)
			(effects
				(font
					(size 1.27 1.27)
					(thickness 0.15)
				)
				(justify left bottom)
				(hide yes)
			)
		)
		(property "Author" "Antmicro"
			(at 379.73 93.98 0)
			(effects
				(font
					(size 1.27 1.27)
					(thickness 0.15)
				)
				(justify left bottom)
				(hide yes)
			)
		)
		(property "Val" "22u"
			(at 356.108 113.03 90)
			(effects
				(font
					(size 1.27 1.27)
					(thickness 0.15)
				)
				(justify right)
			)
		)
		(property "Voltage" "16V"
			(at 356.87 114.2935 90)
			(effects
				(font
					(size 1.27 1.27)
				)
				(justify right)
				(hide yes)
			)
		)
		(property "Dielectric" ""
			(at 384.81 93.98 0)
			(effects
				(font
					(size 1.27 1.27)
				)
				(justify left bottom)
				(hide yes)
			)
		)
		(pin "2"
		)
		(pin "1"
		)
		(instances
			(project "thunderbolt-to-10gbe-adapter"
				(path ""
					(reference "C141")
					(unit 1)
				)
			)
		)
	)
	(symbol
		(lib_id "antmicroLEDIndicationDiscrete:LED_G_0603_LG_L29K-G2J1-24-Z")
		(at 254 223.52 90)
		(unit 1)
		(exclude_from_sim no)
		(in_bom yes)
		(on_board yes)
		(dnp no)
		(property "Reference" "D9"
			(at 255.27 219.71 90)
			(effects
				(font
					(size 1.27 1.27)
					(thickness 0.15)
				)
				(justify right)
			)
		)
		(property "Value" "LED_G_0603_LG_L29K-G2J1-24-Z"
			(at 261.62 203.2 0)
			(effects
				(font
					(size 1.27 1.27)
					(thickness 0.15)
				)
				(justify left bottom)
				(hide yes)
			)
		)
		(property "Footprint" "antmicro-footprints:LED_0603_1608Metric_G"
			(at 264.16 203.2 0)
			(effects
				(font
					(size 1.27 1.27)
					(thickness 0.15)
				)
				(justify left bottom)
				(hide yes)
			)
		)
		(property "Datasheet" "https://look.ams-osram.com/m/19ee86b3ae0ee95b/original/LG-L29K.pdf"
			(at 266.7 203.2 0)
			(effects
				(font
					(size 1.27 1.27)
					(thickness 0.15)
				)
				(justify left bottom)
				(hide yes)
			)
		)
		(property "Description" "LED, Green, SMD, 0603, 20 mA, 1.7 V, 570 nm"
			(at 254 223.52 0)
			(effects
				(font
					(size 1.27 1.27)
				)
				(hide yes)
			)
		)
		(property "MPN" "LG L29K-G2J1-24-Z"
			(at 269.24 203.2 0)
			(effects
				(font
					(size 1.27 1.27)
					(thickness 0.15)
				)
				(justify left bottom)
				(hide yes)
			)
		)
		(property "Manufacturer" "OSRAM"
			(at 271.78 203.2 0)
			(effects
				(font
					(size 1.27 1.27)
					(thickness 0.15)
				)
				(justify left bottom)
				(hide yes)
			)
		)
		(property "Color" "Green"
			(at 255.27 222.2499 90)
			(effects
				(font
					(size 1.27 1.27)
				)
				(justify right)
			)
		)
		(property "Author" "Antmicro"
			(at 274.32 203.2 0)
			(effects
				(font
					(size 1.27 1.27)
					(thickness 0.15)
				)
				(justify left bottom)
				(hide yes)
			)
		)
		(property "License" "Apache-2.0"
			(at 276.86 203.2 0)
			(effects
				(font
					(size 1.27 1.27)
					(thickness 0.15)
				)
				(justify left bottom)
				(hide yes)
			)
		)
		(pin "2"
		)
		(pin "1"
		)
		(instances
			(project "thunderbolt-to-10gbe-adapter"
				(path ""
					(reference "D9")
					(unit 1)
				)
			)
		)
	)
	(symbol
		(lib_id "antmicropower:PWR_FLAG")
		(at 391.16 137.16 0)
		(unit 1)
		(exclude_from_sim no)
		(in_bom yes)
		(on_board yes)
		(dnp no)
		(property "Reference" "#FLG022"
			(at 391.16 135.255 0)
			(effects
				(font
					(size 1.27 1.27)
				)
				(hide yes)
			)
		)
		(property "Value" "PWR_FLAG"
			(at 391.16 133.35 0)
			(effects
				(font
					(size 1.27 1.27)
				)
			)
		)
		(property "Footprint" ""
			(at 391.16 137.16 0)
			(effects
				(font
					(size 1.27 1.27)
				)
				(hide yes)
			)
		)
		(property "Datasheet" ""
			(at 391.16 137.16 0)
			(effects
				(font
					(size 1.27 1.27)
				)
				(hide yes)
			)
		)
		(property "Description" ""
			(at 391.16 137.16 0)
			(effects
				(font
					(size 1.27 1.27)
				)
				(hide yes)
			)
		)
		(pin "1"
		)
		(instances
			(project "thunderbolt-to-10gbe-adapter"
				(path ""
					(reference "#FLG022")
					(unit 1)
				)
			)
		)
	)
	(symbol
		(lib_id "antmicropower:GND")
		(at 374.65 157.48 0)
		(unit 1)
		(exclude_from_sim no)
		(in_bom yes)
		(on_board yes)
		(dnp no)
		(property "Reference" "#PWR0206"
			(at 383.54 160.02 0)
			(effects
				(font
					(size 1.27 1.27)
					(thickness 0.15)
				)
				(justify left bottom)
				(hide yes)
			)
		)
		(property "Value" "GND"
			(at 374.65 161.29 0)
			(effects
				(font
					(size 1.27 1.27)
					(thickness 0.15)
				)
			)
		)
		(property "Footprint" ""
			(at 383.54 165.1 0)
			(effects
				(font
					(size 1.27 1.27)
					(thickness 0.15)
				)
				(justify left bottom)
				(hide yes)
			)
		)
		(property "Datasheet" ""
			(at 383.54 170.18 0)
			(effects
				(font
					(size 1.27 1.27)
					(thickness 0.15)
				)
				(justify left bottom)
				(hide yes)
			)
		)
		(property "Description" ""
			(at 374.65 157.48 0)
			(effects
				(font
					(size 1.27 1.27)
				)
				(hide yes)
			)
		)
		(property "Author" "Antmicro"
			(at 383.54 165.1 0)
			(effects
				(font
					(size 1.27 1.27)
					(thickness 0.15)
				)
				(justify left bottom)
				(hide yes)
			)
		)
		(property "License" "Apache-2.0"
			(at 383.54 167.64 0)
			(effects
				(font
					(size 1.27 1.27)
					(thickness 0.15)
				)
				(justify left bottom)
				(hide yes)
			)
		)
		(pin "1"
		)
		(instances
			(project "thunderbolt-to-10gbe-adapter"
				(path ""
					(reference "#PWR0206")
					(unit 1)
				)
			)
		)
	)
	(symbol
		(lib_id "antmicroCapacitors0402:C_100n_0402")
		(at 307.34 68.58 270)
		(mirror x)
		(unit 1)
		(exclude_from_sim no)
		(in_bom yes)
		(on_board yes)
		(dnp no)
		(property "Reference" "C125"
			(at 309.118 65.024 90)
			(effects
				(font
					(size 1.27 1.27)
					(thickness 0.15)
				)
				(justify left)
			)
		)
		(property "Value" "C_100n_0402"
			(at 297.18 48.26 0)
			(effects
				(font
					(size 1.27 1.27)
					(thickness 0.15)
				)
				(justify left bottom)
				(hide yes)
			)
		)
		(property "Footprint" "antmicro-footprints:C_0402_1005Metric"
			(at 294.64 48.26 0)
			(effects
				(font
					(size 1.27 1.27)
					(thickness 0.15)
				)
				(justify left bottom)
				(hide yes)
			)
		)
		(property "Datasheet" "https://www.murata.com/products/productdetail?partno=GRM155R61H104KE14%23"
			(at 292.1 48.26 0)
			(effects
				(font
					(size 1.27 1.27)
					(thickness 0.15)
				)
				(justify left bottom)
				(hide yes)
			)
		)
		(property "Description" "SMD Multilayer Ceramic Capacitor, 0.1 µF, 50 V, 0402 [1005 Metric], ± 10%, X5R, GRM Series"
			(at 274.32 48.26 0)
			(effects
				(font
					(size 1.27 1.27)
				)
				(justify left bottom)
				(hide yes)
			)
		)
		(property "MPN" "GRM155R61H104KE14D"
			(at 289.56 48.26 0)
			(effects
				(font
					(size 1.27 1.27)
					(thickness 0.15)
				)
				(justify left bottom)
				(hide yes)
			)
		)
		(property "Manufacturer" "Murata"
			(at 287.02 48.26 0)
			(effects
				(font
					(size 1.27 1.27)
					(thickness 0.15)
				)
				(justify left bottom)
				(hide yes)
			)
		)
		(property "License" "Apache-2.0"
			(at 284.48 48.26 0)
			(effects
				(font
					(size 1.27 1.27)
					(thickness 0.15)
				)
				(justify left bottom)
				(hide yes)
			)
		)
		(property "Author" "Antmicro"
			(at 281.94 48.26 0)
			(effects
				(font
					(size 1.27 1.27)
					(thickness 0.15)
				)
				(justify left bottom)
				(hide yes)
			)
		)
		(property "Val" "100n"
			(at 309.118 67.564 90)
			(effects
				(font
					(size 1.27 1.27)
					(thickness 0.15)
				)
				(justify left)
			)
		)
		(property "Voltage" "50V"
			(at 279.4 48.26 0)
			(effects
				(font
					(size 1.27 1.27)
				)
				(justify left bottom)
				(hide yes)
			)
		)
		(property "Dielectric" "X5R"
			(at 276.86 48.26 0)
			(effects
				(font
					(size 1.27 1.27)
				)
				(justify left bottom)
				(hide yes)
			)
		)
		(pin "1"
		)
		(pin "2"
		)
		(instances
			(project "thunderbolt-to-10gbe-adapter"
				(path ""
					(reference "C125")
					(unit 1)
				)
			)
		)
	)
	(symbol
		(lib_id "antmicroResistors0402:R_30k_0402")
		(at 332.74 194.31 90)
		(unit 1)
		(exclude_from_sim no)
		(in_bom yes)
		(on_board yes)
		(dnp no)
		(property "Reference" "R107"
			(at 334.01 190.5 90)
			(effects
				(font
					(size 1.27 1.27)
					(thickness 0.15)
				)
				(justify right)
			)
		)
		(property "Value" "R_30k_0402"
			(at 345.44 173.99 0)
			(effects
				(font
					(size 1.27 1.27)
					(thickness 0.15)
				)
				(justify left bottom)
				(hide yes)
			)
		)
		(property "Footprint" "antmicro-footprints:R_0402_1005Metric"
			(at 347.98 173.99 0)
			(effects
				(font
					(size 1.27 1.27)
					(thickness 0.15)
				)
				(justify left bottom)
				(hide yes)
			)
		)
		(property "Datasheet" "https://www.bourns.com/docs/product-datasheets/cr.pdf"
			(at 350.52 173.99 0)
			(effects
				(font
					(size 1.27 1.27)
					(thickness 0.15)
				)
				(justify left bottom)
				(hide yes)
			)
		)
		(property "Description" "SMD Chip Resistor, 30 kohm, ± 1%, 63 mW, 0402 [1005 Metric], Thick Film, General Purpose"
			(at 363.22 173.99 0)
			(effects
				(font
					(size 1.27 1.27)
				)
				(justify left bottom)
				(hide yes)
			)
		)
		(property "MPN" "CR0402-FX-3002GLF"
			(at 353.06 173.99 0)
			(effects
				(font
					(size 1.27 1.27)
					(thickness 0.15)
				)
				(justify left bottom)
				(hide yes)
			)
		)
		(property "Manufacturer" "Bourns"
			(at 355.6 173.99 0)
			(effects
				(font
					(size 1.27 1.27)
					(thickness 0.15)
				)
				(justify left bottom)
				(hide yes)
			)
		)
		(property "License" "Apache-2.0"
			(at 358.14 173.99 0)
			(effects
				(font
					(size 1.27 1.27)
					(thickness 0.15)
				)
				(justify left bottom)
				(hide yes)
			)
		)
		(property "Author" "Antmicro"
			(at 360.68 173.99 0)
			(effects
				(font
					(size 1.27 1.27)
					(thickness 0.15)
				)
				(justify left bottom)
				(hide yes)
			)
		)
		(property "Val" "30k"
			(at 334.01 193.04 90)
			(effects
				(font
					(size 1.27 1.27)
					(thickness 0.15)
				)
				(justify right)
			)
		)
		(property "Tolerance" "1%"
			(at 342.9 173.99 0)
			(effects
				(font
					(size 1.27 1.27)
				)
				(justify left bottom)
				(hide yes)
			)
		)
		(pin "2"
		)
		(pin "1"
		)
		(instances
			(project "thunderbolt-to-10gbe-adapter"
				(path ""
					(reference "R107")
					(unit 1)
				)
			)
		)
	)
	(symbol
		(lib_id "antmicroCapacitors0402:C_100n_0402")
		(at 374.65 76.2 90)
		(unit 1)
		(exclude_from_sim no)
		(in_bom yes)
		(on_board yes)
		(dnp no)
		(property "Reference" "C150"
			(at 376.428 72.39 90)
			(effects
				(font
					(size 1.27 1.27)
					(thickness 0.15)
				)
				(justify right)
			)
		)
		(property "Value" "C_100n_0402"
			(at 384.81 55.88 0)
			(effects
				(font
					(size 1.27 1.27)
					(thickness 0.15)
				)
				(justify left bottom)
				(hide yes)
			)
		)
		(property "Footprint" "antmicro-footprints:C_0402_1005Metric"
			(at 387.35 55.88 0)
			(effects
				(font
					(size 1.27 1.27)
					(thickness 0.15)
				)
				(justify left bottom)
				(hide yes)
			)
		)
		(property "Datasheet" "https://www.murata.com/products/productdetail?partno=GRM155R61H104KE14%23"
			(at 389.89 55.88 0)
			(effects
				(font
					(size 1.27 1.27)
					(thickness 0.15)
				)
				(justify left bottom)
				(hide yes)
			)
		)
		(property "Description" "SMD Multilayer Ceramic Capacitor, 0.1 µF, 50 V, 0402 [1005 Metric], ± 10%, X5R, GRM Series"
			(at 407.67 55.88 0)
			(effects
				(font
					(size 1.27 1.27)
				)
				(justify left bottom)
				(hide yes)
			)
		)
		(property "MPN" "GRM155R61H104KE14D"
			(at 392.43 55.88 0)
			(effects
				(font
					(size 1.27 1.27)
					(thickness 0.15)
				)
				(justify left bottom)
				(hide yes)
			)
		)
		(property "Manufacturer" "Murata"
			(at 394.97 55.88 0)
			(effects
				(font
					(size 1.27 1.27)
					(thickness 0.15)
				)
				(justify left bottom)
				(hide yes)
			)
		)
		(property "License" "Apache-2.0"
			(at 397.51 55.88 0)
			(effects
				(font
					(size 1.27 1.27)
					(thickness 0.15)
				)
				(justify left bottom)
				(hide yes)
			)
		)
		(property "Author" "Antmicro"
			(at 400.05 55.88 0)
			(effects
				(font
					(size 1.27 1.27)
					(thickness 0.15)
				)
				(justify left bottom)
				(hide yes)
			)
		)
		(property "Val" "100n"
			(at 376.428 74.93 90)
			(effects
				(font
					(size 1.27 1.27)
					(thickness 0.15)
				)
				(justify right)
			)
		)
		(property "Voltage" "50V"
			(at 402.59 55.88 0)
			(effects
				(font
					(size 1.27 1.27)
				)
				(justify left bottom)
				(hide yes)
			)
		)
		(property "Dielectric" "X5R"
			(at 405.13 55.88 0)
			(effects
				(font
					(size 1.27 1.27)
				)
				(justify left bottom)
				(hide yes)
			)
		)
		(pin "1"
		)
		(pin "2"
		)
		(instances
			(project "thunderbolt-to-10gbe-adapter"
				(path ""
					(reference "C150")
					(unit 1)
				)
			)
		)
	)
	(symbol
		(lib_id "antmicroResistors0402:R_100k_0402")
		(at 256.54 114.3 270)
		(mirror x)
		(unit 1)
		(exclude_from_sim no)
		(in_bom yes)
		(on_board yes)
		(dnp no)
		(property "Reference" "R89"
			(at 255.27 110.49 90)
			(effects
				(font
					(size 1.27 1.27)
					(thickness 0.15)
				)
				(justify right)
			)
		)
		(property "Value" "R_100k_0402"
			(at 243.84 93.98 0)
			(effects
				(font
					(size 1.27 1.27)
					(thickness 0.15)
				)
				(justify left bottom)
				(hide yes)
			)
		)
		(property "Footprint" "antmicro-footprints:R_0402_1005Metric"
			(at 241.3 93.98 0)
			(effects
				(font
					(size 1.27 1.27)
					(thickness 0.15)
				)
				(justify left bottom)
				(hide yes)
			)
		)
		(property "Datasheet" "https://www.bourns.com/docs/product-datasheets/cr.pdf"
			(at 238.76 93.98 0)
			(effects
				(font
					(size 1.27 1.27)
					(thickness 0.15)
				)
				(justify left bottom)
				(hide yes)
			)
		)
		(property "Description" "SMD Chip Resistor, 100 kohm, ± 1%, 62.5 mW, 0402 [1005 Metric], Thick Film, General Purpose"
			(at 226.06 93.98 0)
			(effects
				(font
					(size 1.27 1.27)
				)
				(justify left bottom)
				(hide yes)
			)
		)
		(property "MPN" "CR0402-FX-1003GLF"
			(at 236.22 93.98 0)
			(effects
				(font
					(size 1.27 1.27)
					(thickness 0.15)
				)
				(justify left bottom)
				(hide yes)
			)
		)
		(property "Manufacturer" "Bourns"
			(at 233.68 93.98 0)
			(effects
				(font
					(size 1.27 1.27)
					(thickness 0.15)
				)
				(justify left bottom)
				(hide yes)
			)
		)
		(property "License" "Apache-2.0"
			(at 231.14 93.98 0)
			(effects
				(font
					(size 1.27 1.27)
					(thickness 0.15)
				)
				(justify left bottom)
				(hide yes)
			)
		)
		(property "Author" "Antmicro"
			(at 228.6 93.98 0)
			(effects
				(font
					(size 1.27 1.27)
					(thickness 0.15)
				)
				(justify left bottom)
				(hide yes)
			)
		)
		(property "Val" "100k"
			(at 255.27 113.03 90)
			(effects
				(font
					(size 1.27 1.27)
					(thickness 0.15)
				)
				(justify right)
			)
		)
		(property "Tolerance" "1%"
			(at 246.38 93.98 0)
			(effects
				(font
					(size 1.27 1.27)
				)
				(justify left bottom)
				(hide yes)
			)
		)
		(pin "1"
		)
		(pin "2"
		)
		(instances
			(project "thunderbolt-to-10gbe-adapter"
				(path ""
					(reference "R89")
					(unit 1)
				)
			)
		)
	)
	(symbol
		(lib_id "antmicroResistors0402:R_330R_0402")
		(at 228.6 231.14 90)
		(unit 1)
		(exclude_from_sim no)
		(in_bom yes)
		(on_board yes)
		(dnp no)
		(property "Reference" "R85"
			(at 229.87 227.33 90)
			(effects
				(font
					(size 1.27 1.27)
					(thickness 0.15)
				)
				(justify right)
			)
		)
		(property "Value" "R_330R_0402"
			(at 241.3 210.82 0)
			(effects
				(font
					(size 1.27 1.27)
					(thickness 0.15)
				)
				(justify left bottom)
				(hide yes)
			)
		)
		(property "Footprint" "antmicro-footprints:R_0402_1005Metric"
			(at 243.84 210.82 0)
			(effects
				(font
					(size 1.27 1.27)
					(thickness 0.15)
				)
				(justify left bottom)
				(hide yes)
			)
		)
		(property "Datasheet" "https://www.bourns.com/docs/product-datasheets/cr.pdf"
			(at 246.38 210.82 0)
			(effects
				(font
					(size 1.27 1.27)
					(thickness 0.15)
				)
				(justify left bottom)
				(hide yes)
			)
		)
		(property "Description" "SMD Chip Resistor, 330 ohm, ± 1%, 62.5 mW, 0402 [1005 Metric], Thick Film, General Purpose"
			(at 259.08 210.82 0)
			(effects
				(font
					(size 1.27 1.27)
				)
				(justify left bottom)
				(hide yes)
			)
		)
		(property "MPN" "CR0402-FX-3300GLF"
			(at 248.92 210.82 0)
			(effects
				(font
					(size 1.27 1.27)
					(thickness 0.15)
				)
				(justify left bottom)
				(hide yes)
			)
		)
		(property "Manufacturer" "Bourns"
			(at 251.46 210.82 0)
			(effects
				(font
					(size 1.27 1.27)
					(thickness 0.15)
				)
				(justify left bottom)
				(hide yes)
			)
		)
		(property "License" "Apache-2.0"
			(at 254 210.82 0)
			(effects
				(font
					(size 1.27 1.27)
					(thickness 0.15)
				)
				(justify left bottom)
				(hide yes)
			)
		)
		(property "Author" "Antmicro"
			(at 256.54 210.82 0)
			(effects
				(font
					(size 1.27 1.27)
					(thickness 0.15)
				)
				(justify left bottom)
				(hide yes)
			)
		)
		(property "Val" "330R"
			(at 229.87 229.87 90)
			(effects
				(font
					(size 1.27 1.27)
					(thickness 0.15)
				)
				(justify right)
			)
		)
		(property "Tolerance" "1%"
			(at 238.76 210.82 0)
			(effects
				(font
					(size 1.27 1.27)
				)
				(justify left bottom)
				(hide yes)
			)
		)
		(pin "2"
		)
		(pin "1"
		)
		(instances
			(project "thunderbolt-to-10gbe-adapter"
				(path ""
					(reference "R85")
					(unit 1)
				)
			)
		)
	)
	(symbol
		(lib_id "antmicropower:+1V8")
		(at 387.35 233.68 90)
		(unit 1)
		(exclude_from_sim no)
		(in_bom yes)
		(on_board yes)
		(dnp no)
		(fields_autoplaced yes)
		(property "Reference" "#PWR0210"
			(at 389.89 218.44 0)
			(effects
				(font
					(size 1.27 1.27)
					(thickness 0.15)
				)
				(justify left bottom)
				(hide yes)
			)
		)
		(property "Value" "+1V88"
			(at 383.54 233.68 90)
			(effects
				(font
					(size 1.27 1.27)
					(thickness 0.15)
				)
				(justify left)
			)
		)
		(property "Footprint" ""
			(at 394.97 218.44 0)
			(effects
				(font
					(size 1.27 1.27)
					(thickness 0.15)
				)
				(justify left bottom)
				(hide yes)
			)
		)
		(property "Datasheet" ""
			(at 397.51 218.44 0)
			(effects
				(font
					(size 1.27 1.27)
					(thickness 0.15)
				)
				(justify left bottom)
				(hide yes)
			)
		)
		(property "Description" ""
			(at 387.35 233.68 0)
			(effects
				(font
					(size 1.27 1.27)
				)
				(hide yes)
			)
		)
		(property "Author" "Antmicro"
			(at 392.43 218.44 0)
			(effects
				(font
					(size 1.27 1.27)
					(thickness 0.15)
				)
				(justify left bottom)
				(hide yes)
			)
		)
		(property "License" "Apache-2.0"
			(at 394.97 218.44 0)
			(effects
				(font
					(size 1.27 1.27)
					(thickness 0.15)
				)
				(justify left bottom)
				(hide yes)
			)
		)
		(pin "1"
		)
		(instances
			(project "thunderbolt-to-10gbe-adapter"
				(path ""
					(reference "#PWR0210")
					(unit 1)
				)
			)
		)
	)
	(symbol
		(lib_id "antmicropower:GND")
		(at 228.6 246.38 0)
		(mirror y)
		(unit 1)
		(exclude_from_sim no)
		(in_bom yes)
		(on_board yes)
		(dnp no)
		(property "Reference" "#PWR0164"
			(at 219.71 248.92 0)
			(effects
				(font
					(size 1.27 1.27)
					(thickness 0.15)
				)
				(justify left bottom)
				(hide yes)
			)
		)
		(property "Value" "GND"
			(at 228.6 250.19 0)
			(effects
				(font
					(size 1.27 1.27)
					(thickness 0.15)
				)
			)
		)
		(property "Footprint" ""
			(at 219.71 254 0)
			(effects
				(font
					(size 1.27 1.27)
					(thickness 0.15)
				)
				(justify left bottom)
				(hide yes)
			)
		)
		(property "Datasheet" ""
			(at 219.71 259.08 0)
			(effects
				(font
					(size 1.27 1.27)
					(thickness 0.15)
				)
				(justify left bottom)
				(hide yes)
			)
		)
		(property "Description" ""
			(at 228.6 246.38 0)
			(effects
				(font
					(size 1.27 1.27)
				)
				(hide yes)
			)
		)
		(property "Author" "Antmicro"
			(at 219.71 254 0)
			(effects
				(font
					(size 1.27 1.27)
					(thickness 0.15)
				)
				(justify left bottom)
				(hide yes)
			)
		)
		(property "License" "Apache-2.0"
			(at 219.71 256.54 0)
			(effects
				(font
					(size 1.27 1.27)
					(thickness 0.15)
				)
				(justify left bottom)
				(hide yes)
			)
		)
		(pin "1"
		)
		(instances
			(project "thunderbolt-to-10gbe-adapter"
				(path ""
					(reference "#PWR0164")
					(unit 1)
				)
			)
		)
	)
	(symbol
		(lib_id "antmicroCapacitors0603:C_22u_16V_0603")
		(at 217.17 38.1 270)
		(mirror x)
		(unit 1)
		(exclude_from_sim no)
		(in_bom yes)
		(on_board yes)
		(dnp no)
		(property "Reference" "C104"
			(at 215.138 34.29 90)
			(effects
				(font
					(size 1.27 1.27)
					(thickness 0.15)
				)
				(justify right)
			)
		)
		(property "Value" "C_22u_16V_0603"
			(at 207.01 17.78 0)
			(effects
				(font
					(size 1.27 1.27)
					(thickness 0.15)
				)
				(justify left bottom)
				(hide yes)
			)
		)
		(property "Footprint" "antmicro-footprints:C_0603_1608Metric_EIA"
			(at 204.47 17.78 0)
			(effects
				(font
					(size 1.27 1.27)
					(thickness 0.15)
				)
				(justify left bottom)
				(hide yes)
			)
		)
		(property "Datasheet" "https://product.samsungsem.com/mlcc/CL10A226MO7JZN.do"
			(at 201.93 17.78 0)
			(effects
				(font
					(size 1.27 1.27)
					(thickness 0.15)
				)
				(justify left bottom)
				(hide yes)
			)
		)
		(property "Description" "SMD Multilayer Ceramic Capacitor"
			(at 217.17 38.1 0)
			(effects
				(font
					(size 1.27 1.27)
				)
				(hide yes)
			)
		)
		(property "MPN" "CL10A226MO7JZNC"
			(at 199.39 17.78 0)
			(effects
				(font
					(size 1.27 1.27)
					(thickness 0.15)
				)
				(justify left bottom)
				(hide yes)
			)
		)
		(property "Manufacturer" "Samsung Electro-Mechanics"
			(at 196.85 17.78 0)
			(effects
				(font
					(size 1.27 1.27)
					(thickness 0.15)
				)
				(justify left bottom)
				(hide yes)
			)
		)
		(property "License" "Apache-2.0"
			(at 194.31 17.78 0)
			(effects
				(font
					(size 1.27 1.27)
					(thickness 0.15)
				)
				(justify left bottom)
				(hide yes)
			)
		)
		(property "Author" "Antmicro"
			(at 191.77 17.78 0)
			(effects
				(font
					(size 1.27 1.27)
					(thickness 0.15)
				)
				(justify left bottom)
				(hide yes)
			)
		)
		(property "Val" "22u"
			(at 215.138 36.83 90)
			(effects
				(font
					(size 1.27 1.27)
					(thickness 0.15)
				)
				(justify right)
			)
		)
		(property "Voltage" "16V"
			(at 214.63 38.0935 90)
			(effects
				(font
					(size 1.27 1.27)
				)
				(justify right)
				(hide yes)
			)
		)
		(property "Dielectric" ""
			(at 186.69 17.78 0)
			(effects
				(font
					(size 1.27 1.27)
				)
				(justify left bottom)
				(hide yes)
			)
		)
		(pin "2"
		)
		(pin "1"
		)
		(instances
			(project "thunderbolt-to-10gbe-adapter"
				(path ""
					(reference "C104")
					(unit 1)
				)
			)
		)
	)
	(symbol
		(lib_id "antmicropower:GND")
		(at 247.65 157.48 0)
		(unit 1)
		(exclude_from_sim no)
		(in_bom yes)
		(on_board yes)
		(dnp no)
		(property "Reference" "#PWR0173"
			(at 256.54 160.02 0)
			(effects
				(font
					(size 1.27 1.27)
					(thickness 0.15)
				)
				(justify left bottom)
				(hide yes)
			)
		)
		(property "Value" "GND"
			(at 247.65 161.29 0)
			(effects
				(font
					(size 1.27 1.27)
					(thickness 0.15)
				)
			)
		)
		(property "Footprint" ""
			(at 256.54 165.1 0)
			(effects
				(font
					(size 1.27 1.27)
					(thickness 0.15)
				)
				(justify left bottom)
				(hide yes)
			)
		)
		(property "Datasheet" ""
			(at 256.54 170.18 0)
			(effects
				(font
					(size 1.27 1.27)
					(thickness 0.15)
				)
				(justify left bottom)
				(hide yes)
			)
		)
		(property "Description" ""
			(at 247.65 157.48 0)
			(effects
				(font
					(size 1.27 1.27)
				)
				(hide yes)
			)
		)
		(property "Author" "Antmicro"
			(at 256.54 165.1 0)
			(effects
				(font
					(size 1.27 1.27)
					(thickness 0.15)
				)
				(justify left bottom)
				(hide yes)
			)
		)
		(property "License" "Apache-2.0"
			(at 256.54 167.64 0)
			(effects
				(font
					(size 1.27 1.27)
					(thickness 0.15)
				)
				(justify left bottom)
				(hide yes)
			)
		)
		(pin "1"
		)
		(instances
			(project "thunderbolt-to-10gbe-adapter"
				(path ""
					(reference "#PWR0173")
					(unit 1)
				)
			)
		)
	)
	(symbol
		(lib_id "antmicroCapacitors0402:C_33p_0402")
		(at 327.66 33.02 270)
		(mirror x)
		(unit 1)
		(exclude_from_sim no)
		(in_bom yes)
		(on_board yes)
		(dnp no)
		(property "Reference" "C129"
			(at 325.882 29.21 90)
			(effects
				(font
					(size 1.27 1.27)
					(thickness 0.15)
				)
				(justify right)
			)
		)
		(property "Value" "C_33p_0402"
			(at 317.5 12.7 0)
			(effects
				(font
					(size 1.27 1.27)
					(thickness 0.15)
				)
				(justify left bottom)
				(hide yes)
			)
		)
		(property "Footprint" "antmicro-footprints:C_0402_1005Metric"
			(at 314.96 12.7 0)
			(effects
				(font
					(size 1.27 1.27)
					(thickness 0.15)
				)
				(justify left bottom)
				(hide yes)
			)
		)
		(property "Datasheet" "https://spicat.kyocera-avx.com/product/mlcc/chartview/04025A330FAT2A/"
			(at 312.42 12.7 0)
			(effects
				(font
					(size 1.27 1.27)
					(thickness 0.15)
				)
				(justify left bottom)
				(hide yes)
			)
		)
		(property "Description" "SMD Multilayer Ceramic Capacitor, 33 pF, 50 V, 0402 [1005 Metric], ± 5%, C0G / NP0, MC"
			(at 294.64 12.7 0)
			(effects
				(font
					(size 1.27 1.27)
				)
				(justify left bottom)
				(hide yes)
			)
		)
		(property "MPN" "04025A330FAT2A"
			(at 309.88 12.7 0)
			(effects
				(font
					(size 1.27 1.27)
					(thickness 0.15)
				)
				(justify left bottom)
				(hide yes)
			)
		)
		(property "Manufacturer" "KYOCERA AVX"
			(at 307.34 12.7 0)
			(effects
				(font
					(size 1.27 1.27)
					(thickness 0.15)
				)
				(justify left bottom)
				(hide yes)
			)
		)
		(property "License" "Apache-2.0"
			(at 304.8 12.7 0)
			(effects
				(font
					(size 1.27 1.27)
					(thickness 0.15)
				)
				(justify left bottom)
				(hide yes)
			)
		)
		(property "Author" "Antmicro"
			(at 302.26 12.7 0)
			(effects
				(font
					(size 1.27 1.27)
					(thickness 0.15)
				)
				(justify left bottom)
				(hide yes)
			)
		)
		(property "Val" "33p"
			(at 325.882 31.75 90)
			(effects
				(font
					(size 1.27 1.27)
					(thickness 0.15)
				)
				(justify right)
			)
		)
		(property "Voltage" ""
			(at 299.72 12.7 0)
			(effects
				(font
					(size 1.27 1.27)
				)
				(justify left bottom)
				(hide yes)
			)
		)
		(property "Dielectric" ""
			(at 297.18 12.7 0)
			(effects
				(font
					(size 1.27 1.27)
				)
				(justify left bottom)
				(hide yes)
			)
		)
		(pin "2"
		)
		(pin "1"
		)
		(instances
			(project "thunderbolt-to-10gbe-adapter"
				(path ""
					(reference "C129")
					(unit 1)
				)
			)
		)
	)
	(symbol
		(lib_id "antmicroCapacitors0603:C_22u_16V_0603")
		(at 344.17 190.5 90)
		(unit 1)
		(exclude_from_sim no)
		(in_bom yes)
		(on_board yes)
		(dnp no)
		(property "Reference" "C138"
			(at 346.202 186.69 90)
			(effects
				(font
					(size 1.27 1.27)
					(thickness 0.15)
				)
				(justify right)
			)
		)
		(property "Value" "C_22u_16V_0603"
			(at 354.33 170.18 0)
			(effects
				(font
					(size 1.27 1.27)
					(thickness 0.15)
				)
				(justify left bottom)
				(hide yes)
			)
		)
		(property "Footprint" "antmicro-footprints:C_0603_1608Metric_EIA"
			(at 356.87 170.18 0)
			(effects
				(font
					(size 1.27 1.27)
					(thickness 0.15)
				)
				(justify left bottom)
				(hide yes)
			)
		)
		(property "Datasheet" "https://product.samsungsem.com/mlcc/CL10A226MO7JZN.do"
			(at 359.41 170.18 0)
			(effects
				(font
					(size 1.27 1.27)
					(thickness 0.15)
				)
				(justify left bottom)
				(hide yes)
			)
		)
		(property "Description" "SMD Multilayer Ceramic Capacitor"
			(at 344.17 190.5 0)
			(effects
				(font
					(size 1.27 1.27)
				)
				(hide yes)
			)
		)
		(property "MPN" "CL10A226MO7JZNC"
			(at 361.95 170.18 0)
			(effects
				(font
					(size 1.27 1.27)
					(thickness 0.15)
				)
				(justify left bottom)
				(hide yes)
			)
		)
		(property "Manufacturer" "Samsung Electro-Mechanics"
			(at 364.49 170.18 0)
			(effects
				(font
					(size 1.27 1.27)
					(thickness 0.15)
				)
				(justify left bottom)
				(hide yes)
			)
		)
		(property "License" "Apache-2.0"
			(at 367.03 170.18 0)
			(effects
				(font
					(size 1.27 1.27)
					(thickness 0.15)
				)
				(justify left bottom)
				(hide yes)
			)
		)
		(property "Author" "Antmicro"
			(at 369.57 170.18 0)
			(effects
				(font
					(size 1.27 1.27)
					(thickness 0.15)
				)
				(justify left bottom)
				(hide yes)
			)
		)
		(property "Val" "22u"
			(at 346.202 189.23 90)
			(effects
				(font
					(size 1.27 1.27)
					(thickness 0.15)
				)
				(justify right)
			)
		)
		(property "Voltage" "16V"
			(at 346.71 190.4935 90)
			(effects
				(font
					(size 1.27 1.27)
				)
				(justify right)
				(hide yes)
			)
		)
		(property "Dielectric" ""
			(at 374.65 170.18 0)
			(effects
				(font
					(size 1.27 1.27)
				)
				(justify left bottom)
				(hide yes)
			)
		)
		(pin "2"
		)
		(pin "1"
		)
		(instances
			(project "thunderbolt-to-10gbe-adapter"
				(path ""
					(reference "C138")
					(unit 1)
				)
			)
		)
	)
	(symbol
		(lib_id "antmicroCapacitors0603:C_22u_16V_0603")
		(at 344.17 38.1 90)
		(unit 1)
		(exclude_from_sim no)
		(in_bom yes)
		(on_board yes)
		(dnp no)
		(property "Reference" "C134"
			(at 346.202 34.29 90)
			(effects
				(font
					(size 1.27 1.27)
					(thickness 0.15)
				)
				(justify right)
			)
		)
		(property "Value" "C_22u_16V_0603"
			(at 354.33 17.78 0)
			(effects
				(font
					(size 1.27 1.27)
					(thickness 0.15)
				)
				(justify left bottom)
				(hide yes)
			)
		)
		(property "Footprint" "antmicro-footprints:C_0603_1608Metric_EIA"
			(at 356.87 17.78 0)
			(effects
				(font
					(size 1.27 1.27)
					(thickness 0.15)
				)
				(justify left bottom)
				(hide yes)
			)
		)
		(property "Datasheet" "https://product.samsungsem.com/mlcc/CL10A226MO7JZN.do"
			(at 359.41 17.78 0)
			(effects
				(font
					(size 1.27 1.27)
					(thickness 0.15)
				)
				(justify left bottom)
				(hide yes)
			)
		)
		(property "Description" "SMD Multilayer Ceramic Capacitor"
			(at 344.17 38.1 0)
			(effects
				(font
					(size 1.27 1.27)
				)
				(hide yes)
			)
		)
		(property "MPN" "CL10A226MO7JZNC"
			(at 361.95 17.78 0)
			(effects
				(font
					(size 1.27 1.27)
					(thickness 0.15)
				)
				(justify left bottom)
				(hide yes)
			)
		)
		(property "Manufacturer" "Samsung Electro-Mechanics"
			(at 364.49 17.78 0)
			(effects
				(font
					(size 1.27 1.27)
					(thickness 0.15)
				)
				(justify left bottom)
				(hide yes)
			)
		)
		(property "License" "Apache-2.0"
			(at 367.03 17.78 0)
			(effects
				(font
					(size 1.27 1.27)
					(thickness 0.15)
				)
				(justify left bottom)
				(hide yes)
			)
		)
		(property "Author" "Antmicro"
			(at 369.57 17.78 0)
			(effects
				(font
					(size 1.27 1.27)
					(thickness 0.15)
				)
				(justify left bottom)
				(hide yes)
			)
		)
		(property "Val" "22u"
			(at 346.202 36.83 90)
			(effects
				(font
					(size 1.27 1.27)
					(thickness 0.15)
				)
				(justify right)
			)
		)
		(property "Voltage" "16V"
			(at 346.71 38.0935 90)
			(effects
				(font
					(size 1.27 1.27)
				)
				(justify right)
				(hide yes)
			)
		)
		(property "Dielectric" ""
			(at 374.65 17.78 0)
			(effects
				(font
					(size 1.27 1.27)
				)
				(justify left bottom)
				(hide yes)
			)
		)
		(pin "2"
		)
		(pin "1"
		)
		(instances
			(project "thunderbolt-to-10gbe-adapter"
				(path ""
					(reference "C134")
					(unit 1)
				)
			)
		)
	)
	(symbol
		(lib_id "antmicropower:GND")
		(at 364.49 43.18 0)
		(unit 1)
		(exclude_from_sim no)
		(in_bom yes)
		(on_board yes)
		(dnp no)
		(property "Reference" "#PWR0198"
			(at 373.38 45.72 0)
			(effects
				(font
					(size 1.27 1.27)
					(thickness 0.15)
				)
				(justify left bottom)
				(hide yes)
			)
		)
		(property "Value" "GND"
			(at 364.49 46.99 0)
			(effects
				(font
					(size 1.27 1.27)
					(thickness 0.15)
				)
			)
		)
		(property "Footprint" ""
			(at 373.38 50.8 0)
			(effects
				(font
					(size 1.27 1.27)
					(thickness 0.15)
				)
				(justify left bottom)
				(hide yes)
			)
		)
		(property "Datasheet" ""
			(at 373.38 55.88 0)
			(effects
				(font
					(size 1.27 1.27)
					(thickness 0.15)
				)
				(justify left bottom)
				(hide yes)
			)
		)
		(property "Description" ""
			(at 364.49 43.18 0)
			(effects
				(font
					(size 1.27 1.27)
				)
				(hide yes)
			)
		)
		(property "Author" "Antmicro"
			(at 373.38 50.8 0)
			(effects
				(font
					(size 1.27 1.27)
					(thickness 0.15)
				)
				(justify left bottom)
				(hide yes)
			)
		)
		(property "License" "Apache-2.0"
			(at 373.38 53.34 0)
			(effects
				(font
					(size 1.27 1.27)
					(thickness 0.15)
				)
				(justify left bottom)
				(hide yes)
			)
		)
		(pin "1"
		)
		(instances
			(project "thunderbolt-to-10gbe-adapter"
				(path ""
					(reference "#PWR0198")
					(unit 1)
				)
			)
		)
	)
	(symbol
		(lib_id "antmicropower:PWR_FLAG")
		(at 391.16 60.96 0)
		(unit 1)
		(exclude_from_sim no)
		(in_bom yes)
		(on_board yes)
		(dnp no)
		(property "Reference" "#FLG020"
			(at 391.16 59.055 0)
			(effects
				(font
					(size 1.27 1.27)
				)
				(hide yes)
			)
		)
		(property "Value" "PWR_FLAG"
			(at 391.16 57.15 0)
			(effects
				(font
					(size 1.27 1.27)
				)
			)
		)
		(property "Footprint" ""
			(at 391.16 60.96 0)
			(effects
				(font
					(size 1.27 1.27)
				)
				(hide yes)
			)
		)
		(property "Datasheet" ""
			(at 391.16 60.96 0)
			(effects
				(font
					(size 1.27 1.27)
				)
				(hide yes)
			)
		)
		(property "Description" ""
			(at 391.16 60.96 0)
			(effects
				(font
					(size 1.27 1.27)
				)
				(hide yes)
			)
		)
		(pin "1"
		)
		(instances
			(project "thunderbolt-to-10gbe-adapter"
				(path ""
					(reference "#FLG020")
					(unit 1)
				)
			)
		)
	)
	(symbol
		(lib_id "antmicroResistors0402:R_0R_0402")
		(at 261.62 111.76 0)
		(unit 1)
		(exclude_from_sim no)
		(in_bom yes)
		(on_board yes)
		(dnp no)
		(property "Reference" "R93"
			(at 264.16 109.474 0)
			(effects
				(font
					(size 1.27 1.27)
					(thickness 0.15)
				)
			)
		)
		(property "Value" "R_0R_0402"
			(at 281.94 124.46 0)
			(effects
				(font
					(size 1.27 1.27)
					(thickness 0.15)
				)
				(justify left bottom)
				(hide yes)
			)
		)
		(property "Footprint" "antmicro-footprints:R_0402_1005Metric"
			(at 281.94 127 0)
			(effects
				(font
					(size 1.27 1.27)
					(thickness 0.15)
				)
				(justify left bottom)
				(hide yes)
			)
		)
		(property "Datasheet" "https://industrial.panasonic.com/cdbs/www-data/pdf/RDA0000/AOA0000C301.pdf"
			(at 281.94 129.54 0)
			(effects
				(font
					(size 1.27 1.27)
					(thickness 0.15)
				)
				(justify left bottom)
				(hide yes)
			)
		)
		(property "Description" "SMD Chip Resistor, Jumper, 0 ohm, 100 mW, 0402 [1005 Metric], Thick Film, General Purpose"
			(at 281.94 144.78 0)
			(effects
				(font
					(size 1.27 1.27)
				)
				(justify left bottom)
				(hide yes)
			)
		)
		(property "MPN" "ERJ2GE0R00X"
			(at 281.94 132.08 0)
			(effects
				(font
					(size 1.27 1.27)
					(thickness 0.15)
				)
				(justify left bottom)
				(hide yes)
			)
		)
		(property "Manufacturer" "Panasonic"
			(at 281.94 134.62 0)
			(effects
				(font
					(size 1.27 1.27)
					(thickness 0.15)
				)
				(justify left bottom)
				(hide yes)
			)
		)
		(property "License" "Apache-2.0"
			(at 281.94 137.16 0)
			(effects
				(font
					(size 1.27 1.27)
					(thickness 0.15)
				)
				(justify left bottom)
				(hide yes)
			)
		)
		(property "Author" "Antmicro"
			(at 281.94 139.7 0)
			(effects
				(font
					(size 1.27 1.27)
					(thickness 0.15)
				)
				(justify left bottom)
				(hide yes)
			)
		)
		(property "Val" "0R"
			(at 264.16 114.046 0)
			(effects
				(font
					(size 1.27 1.27)
					(thickness 0.15)
				)
			)
		)
		(property "Tolerance" "~"
			(at 281.94 121.92 0)
			(effects
				(font
					(size 1.27 1.27)
				)
				(justify left bottom)
				(hide yes)
			)
		)
		(property "Current" "1A"
			(at 281.94 142.24 0)
			(effects
				(font
					(size 1.27 1.27)
					(thickness 0.15)
				)
				(justify left bottom)
				(hide yes)
			)
		)
		(pin "2"
		)
		(pin "1"
		)
		(instances
			(project "thunderbolt-to-10gbe-adapter"
				(path ""
					(reference "R93")
					(unit 1)
				)
			)
		)
	)
	(symbol
		(lib_id "antmicroFixedInductors:L_1u_10A_Bourns-SRP4021HMT")
		(at 314.96 177.8 0)
		(unit 1)
		(exclude_from_sim no)
		(in_bom yes)
		(on_board yes)
		(dnp no)
		(fields_autoplaced yes)
		(property "Reference" "L8"
			(at 317.5 172.72 0)
			(effects
				(font
					(size 1.27 1.27)
					(thickness 0.15)
				)
			)
		)
		(property "Value" "L_1u_10A_Bourns-SRP4021HMT"
			(at 330.2 187.96 0)
			(effects
				(font
					(size 1.27 1.27)
					(thickness 0.15)
				)
				(justify left bottom)
				(hide yes)
			)
		)
		(property "Footprint" "antmicro-footprints:L_Bourns-SRP4021HMT"
			(at 330.2 190.5 0)
			(effects
				(font
					(size 1.27 1.27)
					(thickness 0.15)
				)
				(justify left bottom)
				(hide yes)
			)
		)
		(property "Datasheet" "https://www.mouser.com/datasheet/2/54/Bourns_04_01_2025_SRP4021HMT_Datasheet-3580094.pdf"
			(at 330.2 193.04 0)
			(effects
				(font
					(size 1.27 1.27)
					(thickness 0.15)
				)
				(justify left bottom)
				(hide yes)
			)
		)
		(property "Description" "Power Inductors - SMD Ind,4.1x4.2x1.9mm,1uH+/-20%,10A, Shielded"
			(at 330.2 195.58 0)
			(effects
				(font
					(size 1.27 1.27)
					(thickness 0.15)
				)
				(justify left bottom)
				(hide yes)
			)
		)
		(property "Val" "1u/10A"
			(at 317.5 175.26 0)
			(effects
				(font
					(size 1.27 1.27)
					(thickness 0.15)
				)
			)
		)
		(property "Manufacturer" "Bourns"
			(at 330.2 198.12 0)
			(effects
				(font
					(size 1.27 1.27)
					(thickness 0.15)
				)
				(justify left bottom)
				(hide yes)
			)
		)
		(property "MPN" "SRP4021HMT-1R0M"
			(at 330.2 200.66 0)
			(effects
				(font
					(size 1.27 1.27)
					(thickness 0.15)
				)
				(justify left bottom)
				(hide yes)
			)
		)
		(property "ISat" ""
			(at 328.93 194.31 0)
			(effects
				(font
					(size 1.27 1.27)
				)
				(justify left)
				(hide yes)
			)
		)
		(property "Isat" "8A"
			(at 330.2 203.2 0)
			(effects
				(font
					(size 1.27 1.27)
					(thickness 0.15)
				)
				(justify left bottom)
				(hide yes)
			)
		)
		(property "IMax" ""
			(at 328.93 198.12 0)
			(effects
				(font
					(size 1.27 1.27)
					(thickness 0.15)
				)
				(justify left bottom)
				(hide yes)
			)
		)
		(property "Imax" "10A"
			(at 330.2 205.74 0)
			(effects
				(font
					(size 1.27 1.27)
					(thickness 0.15)
				)
				(justify left bottom)
				(hide yes)
			)
		)
		(property "Size" "4.2x4.1"
			(at 330.2 208.28 0)
			(effects
				(font
					(size 1.27 1.27)
					(thickness 0.15)
				)
				(justify left bottom)
				(hide yes)
			)
		)
		(property "Author" "Antmicro"
			(at 330.2 210.82 0)
			(effects
				(font
					(size 1.27 1.27)
					(thickness 0.15)
				)
				(justify left bottom)
				(hide yes)
			)
		)
		(property "License" "Apache-2.0"
			(at 330.2 213.36 0)
			(effects
				(font
					(size 1.27 1.27)
					(thickness 0.15)
				)
				(justify left bottom)
				(hide yes)
			)
		)
		(pin "1"
		)
		(pin "2"
		)
		(instances
			(project "thunderbolt-to-10gbe-adapter"
				(path ""
					(reference "L8")
					(unit 1)
				)
			)
		)
	)
	(symbol
		(lib_id "antmicroCapacitors0402:C_100n_0402")
		(at 307.34 30.48 270)
		(mirror x)
		(unit 1)
		(exclude_from_sim no)
		(in_bom yes)
		(on_board yes)
		(dnp no)
		(property "Reference" "C124"
			(at 309.118 26.924 90)
			(effects
				(font
					(size 1.27 1.27)
					(thickness 0.15)
				)
				(justify left)
			)
		)
		(property "Value" "C_100n_0402"
			(at 297.18 10.16 0)
			(effects
				(font
					(size 1.27 1.27)
					(thickness 0.15)
				)
				(justify left bottom)
				(hide yes)
			)
		)
		(property "Footprint" "antmicro-footprints:C_0402_1005Metric"
			(at 294.64 10.16 0)
			(effects
				(font
					(size 1.27 1.27)
					(thickness 0.15)
				)
				(justify left bottom)
				(hide yes)
			)
		)
		(property "Datasheet" "https://www.murata.com/products/productdetail?partno=GRM155R61H104KE14%23"
			(at 292.1 10.16 0)
			(effects
				(font
					(size 1.27 1.27)
					(thickness 0.15)
				)
				(justify left bottom)
				(hide yes)
			)
		)
		(property "Description" "SMD Multilayer Ceramic Capacitor, 0.1 µF, 50 V, 0402 [1005 Metric], ± 10%, X5R, GRM Series"
			(at 274.32 10.16 0)
			(effects
				(font
					(size 1.27 1.27)
				)
				(justify left bottom)
				(hide yes)
			)
		)
		(property "MPN" "GRM155R61H104KE14D"
			(at 289.56 10.16 0)
			(effects
				(font
					(size 1.27 1.27)
					(thickness 0.15)
				)
				(justify left bottom)
				(hide yes)
			)
		)
		(property "Manufacturer" "Murata"
			(at 287.02 10.16 0)
			(effects
				(font
					(size 1.27 1.27)
					(thickness 0.15)
				)
				(justify left bottom)
				(hide yes)
			)
		)
		(property "License" "Apache-2.0"
			(at 284.48 10.16 0)
			(effects
				(font
					(size 1.27 1.27)
					(thickness 0.15)
				)
				(justify left bottom)
				(hide yes)
			)
		)
		(property "Author" "Antmicro"
			(at 281.94 10.16 0)
			(effects
				(font
					(size 1.27 1.27)
					(thickness 0.15)
				)
				(justify left bottom)
				(hide yes)
			)
		)
		(property "Val" "100n"
			(at 309.118 29.464 90)
			(effects
				(font
					(size 1.27 1.27)
					(thickness 0.15)
				)
				(justify left)
			)
		)
		(property "Voltage" "50V"
			(at 279.4 10.16 0)
			(effects
				(font
					(size 1.27 1.27)
				)
				(justify left bottom)
				(hide yes)
			)
		)
		(property "Dielectric" "X5R"
			(at 276.86 10.16 0)
			(effects
				(font
					(size 1.27 1.27)
				)
				(justify left bottom)
				(hide yes)
			)
		)
		(pin "1"
		)
		(pin "2"
		)
		(instances
			(project "thunderbolt-to-10gbe-adapter"
				(path ""
					(reference "C124")
					(unit 1)
				)
			)
		)
	)
	(symbol
		(lib_id "antmicroFixedInductors:L_1u_10A_Bourns-SRP4021HMT")
		(at 314.96 101.6 0)
		(unit 1)
		(exclude_from_sim no)
		(in_bom yes)
		(on_board yes)
		(dnp no)
		(fields_autoplaced yes)
		(property "Reference" "L6"
			(at 317.5 96.52 0)
			(effects
				(font
					(size 1.27 1.27)
					(thickness 0.15)
				)
			)
		)
		(property "Value" "L_1u_10A_Bourns-SRP4021HMT"
			(at 330.2 111.76 0)
			(effects
				(font
					(size 1.27 1.27)
					(thickness 0.15)
				)
				(justify left bottom)
				(hide yes)
			)
		)
		(property "Footprint" "antmicro-footprints:L_Bourns-SRP4021HMT"
			(at 330.2 114.3 0)
			(effects
				(font
					(size 1.27 1.27)
					(thickness 0.15)
				)
				(justify left bottom)
				(hide yes)
			)
		)
		(property "Datasheet" "https://www.mouser.com/datasheet/2/54/Bourns_04_01_2025_SRP4021HMT_Datasheet-3580094.pdf"
			(at 330.2 116.84 0)
			(effects
				(font
					(size 1.27 1.27)
					(thickness 0.15)
				)
				(justify left bottom)
				(hide yes)
			)
		)
		(property "Description" "Power Inductors - SMD Ind,4.1x4.2x1.9mm,1uH+/-20%,10A, Shielded"
			(at 330.2 119.38 0)
			(effects
				(font
					(size 1.27 1.27)
					(thickness 0.15)
				)
				(justify left bottom)
				(hide yes)
			)
		)
		(property "Val" "1u/10A"
			(at 317.5 99.06 0)
			(effects
				(font
					(size 1.27 1.27)
					(thickness 0.15)
				)
			)
		)
		(property "Manufacturer" "Bourns"
			(at 330.2 121.92 0)
			(effects
				(font
					(size 1.27 1.27)
					(thickness 0.15)
				)
				(justify left bottom)
				(hide yes)
			)
		)
		(property "MPN" "SRP4021HMT-1R0M"
			(at 330.2 124.46 0)
			(effects
				(font
					(size 1.27 1.27)
					(thickness 0.15)
				)
				(justify left bottom)
				(hide yes)
			)
		)
		(property "ISat" ""
			(at 328.93 118.11 0)
			(effects
				(font
					(size 1.27 1.27)
				)
				(justify left)
				(hide yes)
			)
		)
		(property "Isat" "8A"
			(at 330.2 127 0)
			(effects
				(font
					(size 1.27 1.27)
					(thickness 0.15)
				)
				(justify left bottom)
				(hide yes)
			)
		)
		(property "IMax" ""
			(at 328.93 121.92 0)
			(effects
				(font
					(size 1.27 1.27)
					(thickness 0.15)
				)
				(justify left bottom)
				(hide yes)
			)
		)
		(property "Imax" "10A"
			(at 330.2 129.54 0)
			(effects
				(font
					(size 1.27 1.27)
					(thickness 0.15)
				)
				(justify left bottom)
				(hide yes)
			)
		)
		(property "Size" "4.2x4.1"
			(at 330.2 132.08 0)
			(effects
				(font
					(size 1.27 1.27)
					(thickness 0.15)
				)
				(justify left bottom)
				(hide yes)
			)
		)
		(property "Author" "Antmicro"
			(at 330.2 134.62 0)
			(effects
				(font
					(size 1.27 1.27)
					(thickness 0.15)
				)
				(justify left bottom)
				(hide yes)
			)
		)
		(property "License" "Apache-2.0"
			(at 330.2 137.16 0)
			(effects
				(font
					(size 1.27 1.27)
					(thickness 0.15)
				)
				(justify left bottom)
				(hide yes)
			)
		)
		(pin "1"
		)
		(pin "2"
		)
		(instances
			(project "thunderbolt-to-10gbe-adapter"
				(path ""
					(reference "L6")
					(unit 1)
				)
			)
		)
	)
	(symbol
		(lib_id "antmicroCapacitors0402:C_100n_0402")
		(at 374.65 152.4 90)
		(unit 1)
		(exclude_from_sim no)
		(in_bom yes)
		(on_board yes)
		(dnp no)
		(property "Reference" "C152"
			(at 376.428 148.59 90)
			(effects
				(font
					(size 1.27 1.27)
					(thickness 0.15)
				)
				(justify right)
			)
		)
		(property "Value" "C_100n_0402"
			(at 384.81 132.08 0)
			(effects
				(font
					(size 1.27 1.27)
					(thickness 0.15)
				)
				(justify left bottom)
				(hide yes)
			)
		)
		(property "Footprint" "antmicro-footprints:C_0402_1005Metric"
			(at 387.35 132.08 0)
			(effects
				(font
					(size 1.27 1.27)
					(thickness 0.15)
				)
				(justify left bottom)
				(hide yes)
			)
		)
		(property "Datasheet" "https://www.murata.com/products/productdetail?partno=GRM155R61H104KE14%23"
			(at 389.89 132.08 0)
			(effects
				(font
					(size 1.27 1.27)
					(thickness 0.15)
				)
				(justify left bottom)
				(hide yes)
			)
		)
		(property "Description" "SMD Multilayer Ceramic Capacitor, 0.1 µF, 50 V, 0402 [1005 Metric], ± 10%, X5R, GRM Series"
			(at 407.67 132.08 0)
			(effects
				(font
					(size 1.27 1.27)
				)
				(justify left bottom)
				(hide yes)
			)
		)
		(property "MPN" "GRM155R61H104KE14D"
			(at 392.43 132.08 0)
			(effects
				(font
					(size 1.27 1.27)
					(thickness 0.15)
				)
				(justify left bottom)
				(hide yes)
			)
		)
		(property "Manufacturer" "Murata"
			(at 394.97 132.08 0)
			(effects
				(font
					(size 1.27 1.27)
					(thickness 0.15)
				)
				(justify left bottom)
				(hide yes)
			)
		)
		(property "License" "Apache-2.0"
			(at 397.51 132.08 0)
			(effects
				(font
					(size 1.27 1.27)
					(thickness 0.15)
				)
				(justify left bottom)
				(hide yes)
			)
		)
		(property "Author" "Antmicro"
			(at 400.05 132.08 0)
			(effects
				(font
					(size 1.27 1.27)
					(thickness 0.15)
				)
				(justify left bottom)
				(hide yes)
			)
		)
		(property "Val" "100n"
			(at 376.428 151.13 90)
			(effects
				(font
					(size 1.27 1.27)
					(thickness 0.15)
				)
				(justify right)
			)
		)
		(property "Voltage" "50V"
			(at 402.59 132.08 0)
			(effects
				(font
					(size 1.27 1.27)
				)
				(justify left bottom)
				(hide yes)
			)
		)
		(property "Dielectric" "X5R"
			(at 405.13 132.08 0)
			(effects
				(font
					(size 1.27 1.27)
				)
				(justify left bottom)
				(hide yes)
			)
		)
		(pin "1"
		)
		(pin "2"
		)
		(instances
			(project "thunderbolt-to-10gbe-adapter"
				(path ""
					(reference "C152")
					(unit 1)
				)
			)
		)
	)
	(symbol
		(lib_id "antmicroTestPoints:TP_0.75mm_SMD")
		(at 391.16 233.68 0)
		(unit 1)
		(exclude_from_sim no)
		(in_bom no)
		(on_board yes)
		(dnp no)
		(fields_autoplaced yes)
		(property "Reference" "TP17"
			(at 396.24 233.68 0)
			(effects
				(font
					(size 1.27 1.27)
					(thickness 0.15)
				)
				(justify left)
			)
		)
		(property "Value" "TP_0.75mm_SMD"
			(at 401.32 237.49 0)
			(effects
				(font
					(size 1.27 1.27)
					(thickness 0.15)
				)
				(justify left bottom)
				(hide yes)
			)
		)
		(property "Footprint" "antmicro-footprints:TP_SMD_0.75mm"
			(at 401.32 240.03 0)
			(effects
				(font
					(size 1.27 1.27)
					(thickness 0.15)
				)
				(justify left bottom)
				(hide yes)
			)
		)
		(property "Datasheet" ""
			(at 408.94 246.38 0)
			(effects
				(font
					(size 1.27 1.27)
					(thickness 0.15)
				)
				(justify left bottom)
				(hide yes)
			)
		)
		(property "Description" "SMT test point"
			(at 401.955 247.65 0)
			(effects
				(font
					(size 1.27 1.27)
				)
				(justify left bottom)
				(hide yes)
			)
		)
		(property "MPN" ""
			(at 401.955 245.11 0)
			(effects
				(font
					(size 1.27 1.27)
					(thickness 0.15)
				)
				(justify left bottom)
				(hide yes)
			)
		)
		(property "Manufacturer" ""
			(at 401.955 240.03 0)
			(effects
				(font
					(size 1.27 1.27)
					(thickness 0.15)
				)
				(justify left bottom)
				(hide yes)
			)
		)
		(property "Author" "Antmicro"
			(at 401.32 242.57 0)
			(effects
				(font
					(size 1.27 1.27)
					(thickness 0.15)
				)
				(justify left bottom)
				(hide yes)
			)
		)
		(property "License" "Apache-2.0"
			(at 401.32 245.11 0)
			(effects
				(font
					(size 1.27 1.27)
					(thickness 0.15)
				)
				(justify left bottom)
				(hide yes)
			)
		)
		(pin "1"
		)
		(instances
			(project "thunderbolt-to-10gbe-adapter"
				(path ""
					(reference "TP17")
					(unit 1)
				)
			)
		)
	)
	(symbol
		(lib_id "antmicroCapacitors0603:C_22u_16V_0603")
		(at 354.33 76.2 90)
		(unit 1)
		(exclude_from_sim no)
		(in_bom yes)
		(on_board yes)
		(dnp no)
		(property "Reference" "C140"
			(at 356.108 72.39 90)
			(effects
				(font
					(size 1.27 1.27)
					(thickness 0.15)
				)
				(justify right)
			)
		)
		(property "Value" "C_22u_16V_0603"
			(at 364.49 55.88 0)
			(effects
				(font
					(size 1.27 1.27)
					(thickness 0.15)
				)
				(justify left bottom)
				(hide yes)
			)
		)
		(property "Footprint" "antmicro-footprints:C_0603_1608Metric_EIA"
			(at 367.03 55.88 0)
			(effects
				(font
					(size 1.27 1.27)
					(thickness 0.15)
				)
				(justify left bottom)
				(hide yes)
			)
		)
		(property "Datasheet" "https://product.samsungsem.com/mlcc/CL10A226MO7JZN.do"
			(at 369.57 55.88 0)
			(effects
				(font
					(size 1.27 1.27)
					(thickness 0.15)
				)
				(justify left bottom)
				(hide yes)
			)
		)
		(property "Description" "SMD Multilayer Ceramic Capacitor"
			(at 354.33 76.2 0)
			(effects
				(font
					(size 1.27 1.27)
				)
				(hide yes)
			)
		)
		(property "MPN" "CL10A226MO7JZNC"
			(at 372.11 55.88 0)
			(effects
				(font
					(size 1.27 1.27)
					(thickness 0.15)
				)
				(justify left bottom)
				(hide yes)
			)
		)
		(property "Manufacturer" "Samsung Electro-Mechanics"
			(at 374.65 55.88 0)
			(effects
				(font
					(size 1.27 1.27)
					(thickness 0.15)
				)
				(justify left bottom)
				(hide yes)
			)
		)
		(property "License" "Apache-2.0"
			(at 377.19 55.88 0)
			(effects
				(font
					(size 1.27 1.27)
					(thickness 0.15)
				)
				(justify left bottom)
				(hide yes)
			)
		)
		(property "Author" "Antmicro"
			(at 379.73 55.88 0)
			(effects
				(font
					(size 1.27 1.27)
					(thickness 0.15)
				)
				(justify left bottom)
				(hide yes)
			)
		)
		(property "Val" "22u"
			(at 356.108 74.93 90)
			(effects
				(font
					(size 1.27 1.27)
					(thickness 0.15)
				)
				(justify right)
			)
		)
		(property "Voltage" "16V"
			(at 356.87 76.1935 90)
			(effects
				(font
					(size 1.27 1.27)
				)
				(justify right)
				(hide yes)
			)
		)
		(property "Dielectric" ""
			(at 384.81 55.88 0)
			(effects
				(font
					(size 1.27 1.27)
				)
				(justify left bottom)
				(hide yes)
			)
		)
		(pin "2"
		)
		(pin "1"
		)
		(instances
			(project "thunderbolt-to-10gbe-adapter"
				(path ""
					(reference "C140")
					(unit 1)
				)
			)
		)
	)
	(symbol
		(lib_id "antmicropower:+5V")
		(at 196.85 22.86 0)
		(unit 1)
		(exclude_from_sim no)
		(in_bom yes)
		(on_board yes)
		(dnp no)
		(property "Reference" "#PWR0148"
			(at 212.09 25.4 0)
			(effects
				(font
					(size 1.27 1.27)
					(thickness 0.15)
				)
				(justify left bottom)
				(hide yes)
			)
		)
		(property "Value" "+5V"
			(at 196.85 19.05 0)
			(effects
				(font
					(size 1.27 1.27)
					(thickness 0.15)
				)
			)
		)
		(property "Footprint" ""
			(at 212.09 30.48 0)
			(effects
				(font
					(size 1.27 1.27)
					(thickness 0.15)
				)
				(justify left bottom)
				(hide yes)
			)
		)
		(property "Datasheet" ""
			(at 212.09 33.02 0)
			(effects
				(font
					(size 1.27 1.27)
					(thickness 0.15)
				)
				(justify left bottom)
				(hide yes)
			)
		)
		(property "Description" ""
			(at 212.09 35.56 0)
			(effects
				(font
					(size 1.27 1.27)
				)
				(justify left bottom)
				(hide yes)
			)
		)
		(property "Author" "Antmicro"
			(at 212.09 30.48 0)
			(effects
				(font
					(size 1.27 1.27)
					(thickness 0.15)
				)
				(justify left bottom)
				(hide yes)
			)
		)
		(property "License" "Apache-2.0"
			(at 212.09 33.02 0)
			(effects
				(font
					(size 1.27 1.27)
					(thickness 0.15)
				)
				(justify left bottom)
				(hide yes)
			)
		)
		(pin "1"
		)
		(instances
			(project "thunderbolt-to-10gbe-adapter"
				(path ""
					(reference "#PWR0148")
					(unit 1)
				)
			)
		)
	)
	(symbol
		(lib_id "antmicropower:GND")
		(at 297.18 43.18 0)
		(unit 1)
		(exclude_from_sim no)
		(in_bom yes)
		(on_board yes)
		(dnp no)
		(property "Reference" "#PWR0177"
			(at 306.07 45.72 0)
			(effects
				(font
					(size 1.27 1.27)
					(thickness 0.15)
				)
				(justify left bottom)
				(hide yes)
			)
		)
		(property "Value" "GND"
			(at 297.18 46.99 0)
			(effects
				(font
					(size 1.27 1.27)
					(thickness 0.15)
				)
			)
		)
		(property "Footprint" ""
			(at 306.07 50.8 0)
			(effects
				(font
					(size 1.27 1.27)
					(thickness 0.15)
				)
				(justify left bottom)
				(hide yes)
			)
		)
		(property "Datasheet" ""
			(at 306.07 55.88 0)
			(effects
				(font
					(size 1.27 1.27)
					(thickness 0.15)
				)
				(justify left bottom)
				(hide yes)
			)
		)
		(property "Description" ""
			(at 297.18 43.18 0)
			(effects
				(font
					(size 1.27 1.27)
				)
				(hide yes)
			)
		)
		(property "Author" "Antmicro"
			(at 306.07 50.8 0)
			(effects
				(font
					(size 1.27 1.27)
					(thickness 0.15)
				)
				(justify left bottom)
				(hide yes)
			)
		)
		(property "License" "Apache-2.0"
			(at 306.07 53.34 0)
			(effects
				(font
					(size 1.27 1.27)
					(thickness 0.15)
				)
				(justify left bottom)
				(hide yes)
			)
		)
		(pin "1"
		)
		(instances
			(project "thunderbolt-to-10gbe-adapter"
				(path ""
					(reference "#PWR0177")
					(unit 1)
				)
			)
		)
	)
	(symbol
		(lib_id "antmicropower:GND")
		(at 237.49 157.48 0)
		(unit 1)
		(exclude_from_sim no)
		(in_bom yes)
		(on_board yes)
		(dnp no)
		(property "Reference" "#PWR0168"
			(at 246.38 160.02 0)
			(effects
				(font
					(size 1.27 1.27)
					(thickness 0.15)
				)
				(justify left bottom)
				(hide yes)
			)
		)
		(property "Value" "GND"
			(at 237.49 161.29 0)
			(effects
				(font
					(size 1.27 1.27)
					(thickness 0.15)
				)
			)
		)
		(property "Footprint" ""
			(at 246.38 165.1 0)
			(effects
				(font
					(size 1.27 1.27)
					(thickness 0.15)
				)
				(justify left bottom)
				(hide yes)
			)
		)
		(property "Datasheet" ""
			(at 246.38 170.18 0)
			(effects
				(font
					(size 1.27 1.27)
					(thickness 0.15)
				)
				(justify left bottom)
				(hide yes)
			)
		)
		(property "Description" ""
			(at 237.49 157.48 0)
			(effects
				(font
					(size 1.27 1.27)
				)
				(hide yes)
			)
		)
		(property "Author" "Antmicro"
			(at 246.38 165.1 0)
			(effects
				(font
					(size 1.27 1.27)
					(thickness 0.15)
				)
				(justify left bottom)
				(hide yes)
			)
		)
		(property "License" "Apache-2.0"
			(at 246.38 167.64 0)
			(effects
				(font
					(size 1.27 1.27)
					(thickness 0.15)
				)
				(justify left bottom)
				(hide yes)
			)
		)
		(pin "1"
		)
		(instances
			(project "thunderbolt-to-10gbe-adapter"
				(path ""
					(reference "#PWR0168")
					(unit 1)
				)
			)
		)
	)
	(symbol
		(lib_id "antmicroCapacitors0603:C_22u_16V_0603")
		(at 364.49 114.3 90)
		(unit 1)
		(exclude_from_sim no)
		(in_bom yes)
		(on_board yes)
		(dnp no)
		(property "Reference" "C146"
			(at 366.268 110.49 90)
			(effects
				(font
					(size 1.27 1.27)
					(thickness 0.15)
				)
				(justify right)
			)
		)
		(property "Value" "C_22u_16V_0603"
			(at 374.65 93.98 0)
			(effects
				(font
					(size 1.27 1.27)
					(thickness 0.15)
				)
				(justify left bottom)
				(hide yes)
			)
		)
		(property "Footprint" "antmicro-footprints:C_0603_1608Metric_EIA"
			(at 377.19 93.98 0)
			(effects
				(font
					(size 1.27 1.27)
					(thickness 0.15)
				)
				(justify left bottom)
				(hide yes)
			)
		)
		(property "Datasheet" "https://product.samsungsem.com/mlcc/CL10A226MO7JZN.do"
			(at 379.73 93.98 0)
			(effects
				(font
					(size 1.27 1.27)
					(thickness 0.15)
				)
				(justify left bottom)
				(hide yes)
			)
		)
		(property "Description" "SMD Multilayer Ceramic Capacitor"
			(at 364.49 114.3 0)
			(effects
				(font
					(size 1.27 1.27)
				)
				(hide yes)
			)
		)
		(property "MPN" "CL10A226MO7JZNC"
			(at 382.27 93.98 0)
			(effects
				(font
					(size 1.27 1.27)
					(thickness 0.15)
				)
				(justify left bottom)
				(hide yes)
			)
		)
		(property "Manufacturer" "Samsung Electro-Mechanics"
			(at 384.81 93.98 0)
			(effects
				(font
					(size 1.27 1.27)
					(thickness 0.15)
				)
				(justify left bottom)
				(hide yes)
			)
		)
		(property "License" "Apache-2.0"
			(at 387.35 93.98 0)
			(effects
				(font
					(size 1.27 1.27)
					(thickness 0.15)
				)
				(justify left bottom)
				(hide yes)
			)
		)
		(property "Author" "Antmicro"
			(at 389.89 93.98 0)
			(effects
				(font
					(size 1.27 1.27)
					(thickness 0.15)
				)
				(justify left bottom)
				(hide yes)
			)
		)
		(property "Val" "22u"
			(at 366.268 113.03 90)
			(effects
				(font
					(size 1.27 1.27)
					(thickness 0.15)
				)
				(justify right)
			)
		)
		(property "Voltage" "16V"
			(at 367.03 114.2935 90)
			(effects
				(font
					(size 1.27 1.27)
				)
				(justify right)
				(hide yes)
			)
		)
		(property "Dielectric" ""
			(at 394.97 93.98 0)
			(effects
				(font
					(size 1.27 1.27)
				)
				(justify left bottom)
				(hide yes)
			)
		)
		(pin "2"
		)
		(pin "1"
		)
		(instances
			(project "thunderbolt-to-10gbe-adapter"
				(path ""
					(reference "C146")
					(unit 1)
				)
			)
		)
	)
	(symbol
		(lib_id "antmicropower:GND")
		(at 332.74 81.28 0)
		(unit 1)
		(exclude_from_sim no)
		(in_bom yes)
		(on_board yes)
		(dnp no)
		(property "Reference" "#PWR0184"
			(at 341.63 83.82 0)
			(effects
				(font
					(size 1.27 1.27)
					(thickness 0.15)
				)
				(justify left bottom)
				(hide yes)
			)
		)
		(property "Value" "GND"
			(at 332.74 85.09 0)
			(effects
				(font
					(size 1.27 1.27)
					(thickness 0.15)
				)
			)
		)
		(property "Footprint" ""
			(at 341.63 88.9 0)
			(effects
				(font
					(size 1.27 1.27)
					(thickness 0.15)
				)
				(justify left bottom)
				(hide yes)
			)
		)
		(property "Datasheet" ""
			(at 341.63 93.98 0)
			(effects
				(font
					(size 1.27 1.27)
					(thickness 0.15)
				)
				(justify left bottom)
				(hide yes)
			)
		)
		(property "Description" ""
			(at 332.74 81.28 0)
			(effects
				(font
					(size 1.27 1.27)
				)
				(hide yes)
			)
		)
		(property "Author" "Antmicro"
			(at 341.63 88.9 0)
			(effects
				(font
					(size 1.27 1.27)
					(thickness 0.15)
				)
				(justify left bottom)
				(hide yes)
			)
		)
		(property "License" "Apache-2.0"
			(at 341.63 91.44 0)
			(effects
				(font
					(size 1.27 1.27)
					(thickness 0.15)
				)
				(justify left bottom)
				(hide yes)
			)
		)
		(pin "1"
		)
		(instances
			(project "thunderbolt-to-10gbe-adapter"
				(path ""
					(reference "#PWR0184")
					(unit 1)
				)
			)
		)
	)
	(symbol
		(lib_id "antmicroLEDIndicationDiscrete:LED_G_0603_LG_L29K-G2J1-24-Z")
		(at 279.4 223.52 90)
		(unit 1)
		(exclude_from_sim no)
		(in_bom yes)
		(on_board yes)
		(dnp no)
		(property "Reference" "D10"
			(at 280.67 219.71 90)
			(effects
				(font
					(size 1.27 1.27)
					(thickness 0.15)
				)
				(justify right)
			)
		)
		(property "Value" "LED_G_0603_LG_L29K-G2J1-24-Z"
			(at 287.02 203.2 0)
			(effects
				(font
					(size 1.27 1.27)
					(thickness 0.15)
				)
				(justify left bottom)
				(hide yes)
			)
		)
		(property "Footprint" "antmicro-footprints:LED_0603_1608Metric_G"
			(at 289.56 203.2 0)
			(effects
				(font
					(size 1.27 1.27)
					(thickness 0.15)
				)
				(justify left bottom)
				(hide yes)
			)
		)
		(property "Datasheet" "https://look.ams-osram.com/m/19ee86b3ae0ee95b/original/LG-L29K.pdf"
			(at 292.1 203.2 0)
			(effects
				(font
					(size 1.27 1.27)
					(thickness 0.15)
				)
				(justify left bottom)
				(hide yes)
			)
		)
		(property "Description" "LED, Green, SMD, 0603, 20 mA, 1.7 V, 570 nm"
			(at 279.4 223.52 0)
			(effects
				(font
					(size 1.27 1.27)
				)
				(hide yes)
			)
		)
		(property "MPN" "LG L29K-G2J1-24-Z"
			(at 294.64 203.2 0)
			(effects
				(font
					(size 1.27 1.27)
					(thickness 0.15)
				)
				(justify left bottom)
				(hide yes)
			)
		)
		(property "Manufacturer" "OSRAM"
			(at 297.18 203.2 0)
			(effects
				(font
					(size 1.27 1.27)
					(thickness 0.15)
				)
				(justify left bottom)
				(hide yes)
			)
		)
		(property "Color" "Green"
			(at 280.67 222.2499 90)
			(effects
				(font
					(size 1.27 1.27)
				)
				(justify right)
			)
		)
		(property "Author" "Antmicro"
			(at 299.72 203.2 0)
			(effects
				(font
					(size 1.27 1.27)
					(thickness 0.15)
				)
				(justify left bottom)
				(hide yes)
			)
		)
		(property "License" "Apache-2.0"
			(at 302.26 203.2 0)
			(effects
				(font
					(size 1.27 1.27)
					(thickness 0.15)
				)
				(justify left bottom)
				(hide yes)
			)
		)
		(pin "2"
		)
		(pin "1"
		)
		(instances
			(project "thunderbolt-to-10gbe-adapter"
				(path ""
					(reference "D10")
					(unit 1)
				)
			)
		)
	)
	(symbol
		(lib_id "antmicroLEDIndicationDiscrete:LED_G_0603_LG_L29K-G2J1-24-Z")
		(at 228.6 223.52 90)
		(unit 1)
		(exclude_from_sim no)
		(in_bom yes)
		(on_board yes)
		(dnp no)
		(property "Reference" "D8"
			(at 229.87 219.71 90)
			(effects
				(font
					(size 1.27 1.27)
					(thickness 0.15)
				)
				(justify right)
			)
		)
		(property "Value" "LED_G_0603_LG_L29K-G2J1-24-Z"
			(at 236.22 203.2 0)
			(effects
				(font
					(size 1.27 1.27)
					(thickness 0.15)
				)
				(justify left bottom)
				(hide yes)
			)
		)
		(property "Footprint" "antmicro-footprints:LED_0603_1608Metric_G"
			(at 238.76 203.2 0)
			(effects
				(font
					(size 1.27 1.27)
					(thickness 0.15)
				)
				(justify left bottom)
				(hide yes)
			)
		)
		(property "Datasheet" "https://look.ams-osram.com/m/19ee86b3ae0ee95b/original/LG-L29K.pdf"
			(at 241.3 203.2 0)
			(effects
				(font
					(size 1.27 1.27)
					(thickness 0.15)
				)
				(justify left bottom)
				(hide yes)
			)
		)
		(property "Description" "LED, Green, SMD, 0603, 20 mA, 1.7 V, 570 nm"
			(at 228.6 223.52 0)
			(effects
				(font
					(size 1.27 1.27)
				)
				(hide yes)
			)
		)
		(property "MPN" "LG L29K-G2J1-24-Z"
			(at 243.84 203.2 0)
			(effects
				(font
					(size 1.27 1.27)
					(thickness 0.15)
				)
				(justify left bottom)
				(hide yes)
			)
		)
		(property "Manufacturer" "OSRAM"
			(at 246.38 203.2 0)
			(effects
				(font
					(size 1.27 1.27)
					(thickness 0.15)
				)
				(justify left bottom)
				(hide yes)
			)
		)
		(property "Color" "Green"
			(at 229.87 222.2499 90)
			(effects
				(font
					(size 1.27 1.27)
				)
				(justify right)
			)
		)
		(property "Author" "Antmicro"
			(at 248.92 203.2 0)
			(effects
				(font
					(size 1.27 1.27)
					(thickness 0.15)
				)
				(justify left bottom)
				(hide yes)
			)
		)
		(property "License" "Apache-2.0"
			(at 251.46 203.2 0)
			(effects
				(font
					(size 1.27 1.27)
					(thickness 0.15)
				)
				(justify left bottom)
				(hide yes)
			)
		)
		(pin "2"
		)
		(pin "1"
		)
		(instances
			(project "thunderbolt-to-10gbe-adapter"
				(path ""
					(reference "D8")
					(unit 1)
				)
			)
		)
	)
	(symbol
		(lib_id "antmicropower:GND")
		(at 247.65 43.18 0)
		(unit 1)
		(exclude_from_sim no)
		(in_bom yes)
		(on_board yes)
		(dnp no)
		(property "Reference" "#PWR0170"
			(at 256.54 45.72 0)
			(effects
				(font
					(size 1.27 1.27)
					(thickness 0.15)
				)
				(justify left bottom)
				(hide yes)
			)
		)
		(property "Value" "GND"
			(at 247.65 46.99 0)
			(effects
				(font
					(size 1.27 1.27)
					(thickness 0.15)
				)
			)
		)
		(property "Footprint" ""
			(at 256.54 50.8 0)
			(effects
				(font
					(size 1.27 1.27)
					(thickness 0.15)
				)
				(justify left bottom)
				(hide yes)
			)
		)
		(property "Datasheet" ""
			(at 256.54 55.88 0)
			(effects
				(font
					(size 1.27 1.27)
					(thickness 0.15)
				)
				(justify left bottom)
				(hide yes)
			)
		)
		(property "Description" ""
			(at 247.65 43.18 0)
			(effects
				(font
					(size 1.27 1.27)
				)
				(hide yes)
			)
		)
		(property "Author" "Antmicro"
			(at 256.54 50.8 0)
			(effects
				(font
					(size 1.27 1.27)
					(thickness 0.15)
				)
				(justify left bottom)
				(hide yes)
			)
		)
		(property "License" "Apache-2.0"
			(at 256.54 53.34 0)
			(effects
				(font
					(size 1.27 1.27)
					(thickness 0.15)
				)
				(justify left bottom)
				(hide yes)
			)
		)
		(pin "1"
		)
		(instances
			(project "thunderbolt-to-10gbe-adapter"
				(path ""
					(reference "#PWR0170")
					(unit 1)
				)
			)
		)
	)
	(symbol
		(lib_id "antmicropower:GND")
		(at 247.65 81.28 0)
		(unit 1)
		(exclude_from_sim no)
		(in_bom yes)
		(on_board yes)
		(dnp no)
		(property "Reference" "#PWR0171"
			(at 256.54 83.82 0)
			(effects
				(font
					(size 1.27 1.27)
					(thickness 0.15)
				)
				(justify left bottom)
				(hide yes)
			)
		)
		(property "Value" "GND"
			(at 247.65 85.09 0)
			(effects
				(font
					(size 1.27 1.27)
					(thickness 0.15)
				)
			)
		)
		(property "Footprint" ""
			(at 256.54 88.9 0)
			(effects
				(font
					(size 1.27 1.27)
					(thickness 0.15)
				)
				(justify left bottom)
				(hide yes)
			)
		)
		(property "Datasheet" ""
			(at 256.54 93.98 0)
			(effects
				(font
					(size 1.27 1.27)
					(thickness 0.15)
				)
				(justify left bottom)
				(hide yes)
			)
		)
		(property "Description" ""
			(at 247.65 81.28 0)
			(effects
				(font
					(size 1.27 1.27)
				)
				(hide yes)
			)
		)
		(property "Author" "Antmicro"
			(at 256.54 88.9 0)
			(effects
				(font
					(size 1.27 1.27)
					(thickness 0.15)
				)
				(justify left bottom)
				(hide yes)
			)
		)
		(property "License" "Apache-2.0"
			(at 256.54 91.44 0)
			(effects
				(font
					(size 1.27 1.27)
					(thickness 0.15)
				)
				(justify left bottom)
				(hide yes)
			)
		)
		(pin "1"
		)
		(instances
			(project "thunderbolt-to-10gbe-adapter"
				(path ""
					(reference "#PWR0171")
					(unit 1)
				)
			)
		)
	)
	(symbol
		(lib_id "antmicroResistors0402:R_100k_0402")
		(at 256.54 190.5 270)
		(mirror x)
		(unit 1)
		(exclude_from_sim no)
		(in_bom yes)
		(on_board yes)
		(dnp no)
		(property "Reference" "R91"
			(at 255.27 186.69 90)
			(effects
				(font
					(size 1.27 1.27)
					(thickness 0.15)
				)
				(justify right)
			)
		)
		(property "Value" "R_100k_0402"
			(at 243.84 170.18 0)
			(effects
				(font
					(size 1.27 1.27)
					(thickness 0.15)
				)
				(justify left bottom)
				(hide yes)
			)
		)
		(property "Footprint" "antmicro-footprints:R_0402_1005Metric"
			(at 241.3 170.18 0)
			(effects
				(font
					(size 1.27 1.27)
					(thickness 0.15)
				)
				(justify left bottom)
				(hide yes)
			)
		)
		(property "Datasheet" "https://www.bourns.com/docs/product-datasheets/cr.pdf"
			(at 238.76 170.18 0)
			(effects
				(font
					(size 1.27 1.27)
					(thickness 0.15)
				)
				(justify left bottom)
				(hide yes)
			)
		)
		(property "Description" "SMD Chip Resistor, 100 kohm, ± 1%, 62.5 mW, 0402 [1005 Metric], Thick Film, General Purpose"
			(at 226.06 170.18 0)
			(effects
				(font
					(size 1.27 1.27)
				)
				(justify left bottom)
				(hide yes)
			)
		)
		(property "MPN" "CR0402-FX-1003GLF"
			(at 236.22 170.18 0)
			(effects
				(font
					(size 1.27 1.27)
					(thickness 0.15)
				)
				(justify left bottom)
				(hide yes)
			)
		)
		(property "Manufacturer" "Bourns"
			(at 233.68 170.18 0)
			(effects
				(font
					(size 1.27 1.27)
					(thickness 0.15)
				)
				(justify left bottom)
				(hide yes)
			)
		)
		(property "License" "Apache-2.0"
			(at 231.14 170.18 0)
			(effects
				(font
					(size 1.27 1.27)
					(thickness 0.15)
				)
				(justify left bottom)
				(hide yes)
			)
		)
		(property "Author" "Antmicro"
			(at 228.6 170.18 0)
			(effects
				(font
					(size 1.27 1.27)
					(thickness 0.15)
				)
				(justify left bottom)
				(hide yes)
			)
		)
		(property "Val" "100k"
			(at 255.27 189.23 90)
			(effects
				(font
					(size 1.27 1.27)
					(thickness 0.15)
				)
				(justify right)
			)
		)
		(property "Tolerance" "1%"
			(at 246.38 170.18 0)
			(effects
				(font
					(size 1.27 1.27)
				)
				(justify left bottom)
				(hide yes)
			)
		)
		(pin "1"
		)
		(pin "2"
		)
		(instances
			(project "thunderbolt-to-10gbe-adapter"
				(path ""
					(reference "R91")
					(unit 1)
				)
			)
		)
	)
	(symbol
		(lib_id "antmicropower:GND")
		(at 297.18 119.38 0)
		(unit 1)
		(exclude_from_sim no)
		(in_bom yes)
		(on_board yes)
		(dnp no)
		(property "Reference" "#PWR0179"
			(at 306.07 121.92 0)
			(effects
				(font
					(size 1.27 1.27)
					(thickness 0.15)
				)
				(justify left bottom)
				(hide yes)
			)
		)
		(property "Value" "GND"
			(at 297.18 123.19 0)
			(effects
				(font
					(size 1.27 1.27)
					(thickness 0.15)
				)
			)
		)
		(property "Footprint" ""
			(at 306.07 127 0)
			(effects
				(font
					(size 1.27 1.27)
					(thickness 0.15)
				)
				(justify left bottom)
				(hide yes)
			)
		)
		(property "Datasheet" ""
			(at 306.07 132.08 0)
			(effects
				(font
					(size 1.27 1.27)
					(thickness 0.15)
				)
				(justify left bottom)
				(hide yes)
			)
		)
		(property "Description" ""
			(at 297.18 119.38 0)
			(effects
				(font
					(size 1.27 1.27)
				)
				(hide yes)
			)
		)
		(property "Author" "Antmicro"
			(at 306.07 127 0)
			(effects
				(font
					(size 1.27 1.27)
					(thickness 0.15)
				)
				(justify left bottom)
				(hide yes)
			)
		)
		(property "License" "Apache-2.0"
			(at 306.07 129.54 0)
			(effects
				(font
					(size 1.27 1.27)
					(thickness 0.15)
				)
				(justify left bottom)
				(hide yes)
			)
		)
		(pin "1"
		)
		(instances
			(project "thunderbolt-to-10gbe-adapter"
				(path ""
					(reference "#PWR0179")
					(unit 1)
				)
			)
		)
	)
	(symbol
		(lib_id "antmicroResistors0603:R_0R_22.4A_0603")
		(at 379.73 63.5 0)
		(unit 1)
		(exclude_from_sim no)
		(in_bom yes)
		(on_board yes)
		(dnp no)
		(property "Reference" "R109"
			(at 379.73 62.23 0)
			(effects
				(font
					(size 1.27 1.27)
					(thickness 0.15)
				)
				(justify right)
			)
		)
		(property "Value" "R_0R_22.4A_0603"
			(at 394.97 68.58 0)
			(effects
				(font
					(size 1.27 1.27)
					(thickness 0.15)
				)
				(justify left bottom)
				(hide yes)
			)
		)
		(property "Footprint" "antmicro-footprints:R_0603_1608Metric"
			(at 394.97 73.66 0)
			(effects
				(font
					(size 1.27 1.27)
					(thickness 0.15)
				)
				(justify left bottom)
				(hide yes)
			)
		)
		(property "Datasheet" "https://fscdn.rohm.com/en/products/databook/datasheet/passive/resistor/chip_resistor/pmr-jpw-e.pdf"
			(at 394.97 76.2 0)
			(effects
				(font
					(size 1.27 1.27)
					(thickness 0.15)
				)
				(justify left bottom)
				(hide yes)
			)
		)
		(property "Description" "SMD Chip Resistor"
			(at 394.97 91.44 0)
			(effects
				(font
					(size 1.27 1.27)
				)
				(justify left bottom)
				(hide yes)
			)
		)
		(property "MPN" "PMR03EZPJ000"
			(at 394.97 78.74 0)
			(effects
				(font
					(size 1.27 1.27)
					(thickness 0.15)
				)
				(justify left bottom)
				(hide yes)
			)
		)
		(property "Manufacturer" "ROHM Semiconductor"
			(at 394.97 81.28 0)
			(effects
				(font
					(size 1.27 1.27)
					(thickness 0.15)
				)
				(justify left bottom)
				(hide yes)
			)
		)
		(property "Val" "0R"
			(at 384.81 62.23 0)
			(effects
				(font
					(size 1.27 1.27)
					(thickness 0.15)
				)
				(justify left)
			)
		)
		(property "Max. Curr." "22.4A"
			(at 382.27 66.04 0)
			(effects
				(font
					(size 1.27 1.27)
					(thickness 0.15)
				)
			)
		)
		(property "Author" "Antmicro"
			(at 394.97 86.36 0)
			(effects
				(font
					(size 1.27 1.27)
					(thickness 0.15)
				)
				(justify left bottom)
				(hide yes)
			)
		)
		(property "License" "Apache-2.0"
			(at 394.97 88.9 0)
			(effects
				(font
					(size 1.27 1.27)
					(thickness 0.15)
				)
				(justify left bottom)
				(hide yes)
			)
		)
		(property "Tolerance" "template_tolerance"
			(at 400.05 73.66 0)
			(effects
				(font
					(size 1.27 1.27)
				)
				(justify left bottom)
				(hide yes)
			)
		)
		(pin "1"
		)
		(pin "2"
		)
		(instances
			(project "thunderbolt-to-10gbe-adapter"
				(path ""
					(reference "R109")
					(unit 1)
				)
			)
		)
	)
	(symbol
		(lib_id "antmicroTransistorsBipolarSingle:DTC014T_SOT-416")
		(at 271.78 238.76 0)
		(unit 1)
		(exclude_from_sim no)
		(in_bom yes)
		(on_board yes)
		(dnp no)
		(property "Reference" "Q5"
			(at 281.178 240.03 0)
			(effects
				(font
					(size 1.27 1.27)
					(thickness 0.15)
				)
				(justify left)
			)
		)
		(property "Value" "DTC014T_SOT-416"
			(at 297.18 246.38 0)
			(effects
				(font
					(size 1.27 1.27)
					(thickness 0.15)
				)
				(justify left bottom)
				(hide yes)
			)
		)
		(property "Footprint" "antmicro-footprints:SOT-416"
			(at 297.18 248.92 0)
			(effects
				(font
					(size 1.27 1.27)
					(thickness 0.15)
				)
				(justify left bottom)
				(hide yes)
			)
		)
		(property "Datasheet" "https://www.rohm.com/datasheet?p=DTC014TEB&dist=Mouser&media=referral&source=mouser.com&campaign=Mouser"
			(at 297.18 251.46 0)
			(effects
				(font
					(size 1.27 1.27)
					(thickness 0.15)
				)
				(justify left bottom)
				(hide yes)
			)
		)
		(property "Description" "Bipolar (BJT) Single Transistor with built-in base resistor, NPN, 50V, 100mA, 150mW, SOT-416FL, Surface Mount"
			(at 297.18 264.16 0)
			(effects
				(font
					(size 1.27 1.27)
				)
				(justify left bottom)
				(hide yes)
			)
		)
		(property "Manufacturer" "ROHM Semiconductor"
			(at 297.18 254 0)
			(effects
				(font
					(size 1.27 1.27)
					(thickness 0.15)
				)
				(justify left bottom)
				(hide yes)
			)
		)
		(property "MPN" "DTC014TEBTL"
			(at 281.178 242.57 0)
			(effects
				(font
					(size 1.27 1.27)
					(thickness 0.15)
				)
				(justify left)
			)
		)
		(property "Author" "Antmicro"
			(at 297.18 259.08 0)
			(effects
				(font
					(size 1.27 1.27)
					(thickness 0.15)
				)
				(justify left bottom)
				(hide yes)
			)
		)
		(property "License" "Apache-2.0"
			(at 297.18 261.62 0)
			(effects
				(font
					(size 1.27 1.27)
					(thickness 0.15)
				)
				(justify left bottom)
				(hide yes)
			)
		)
		(pin "1"
		)
		(pin "2"
		)
		(pin "3"
		)
		(instances
			(project "thunderbolt-to-10gbe-adapter"
				(path ""
					(reference "Q5")
					(unit 1)
				)
			)
		)
	)
	(symbol
		(lib_id "antmicropower:GND")
		(at 354.33 81.28 0)
		(unit 1)
		(exclude_from_sim no)
		(in_bom yes)
		(on_board yes)
		(dnp no)
		(property "Reference" "#PWR0194"
			(at 363.22 83.82 0)
			(effects
				(font
					(size 1.27 1.27)
					(thickness 0.15)
				)
				(justify left bottom)
				(hide yes)
			)
		)
		(property "Value" "GND"
			(at 354.33 85.09 0)
			(effects
				(font
					(size 1.27 1.27)
					(thickness 0.15)
				)
			)
		)
		(property "Footprint" ""
			(at 363.22 88.9 0)
			(effects
				(font
					(size 1.27 1.27)
					(thickness 0.15)
				)
				(justify left bottom)
				(hide yes)
			)
		)
		(property "Datasheet" ""
			(at 363.22 93.98 0)
			(effects
				(font
					(size 1.27 1.27)
					(thickness 0.15)
				)
				(justify left bottom)
				(hide yes)
			)
		)
		(property "Description" ""
			(at 354.33 81.28 0)
			(effects
				(font
					(size 1.27 1.27)
				)
				(hide yes)
			)
		)
		(property "Author" "Antmicro"
			(at 363.22 88.9 0)
			(effects
				(font
					(size 1.27 1.27)
					(thickness 0.15)
				)
				(justify left bottom)
				(hide yes)
			)
		)
		(property "License" "Apache-2.0"
			(at 363.22 91.44 0)
			(effects
				(font
					(size 1.27 1.27)
					(thickness 0.15)
				)
				(justify left bottom)
				(hide yes)
			)
		)
		(pin "1"
		)
		(instances
			(project "thunderbolt-to-10gbe-adapter"
				(path ""
					(reference "#PWR0194")
					(unit 1)
				)
			)
		)
	)
	(symbol
		(lib_id "antmicropower:GND")
		(at 364.49 119.38 0)
		(unit 1)
		(exclude_from_sim no)
		(in_bom yes)
		(on_board yes)
		(dnp no)
		(property "Reference" "#PWR0200"
			(at 373.38 121.92 0)
			(effects
				(font
					(size 1.27 1.27)
					(thickness 0.15)
				)
				(justify left bottom)
				(hide yes)
			)
		)
		(property "Value" "GND"
			(at 364.49 123.19 0)
			(effects
				(font
					(size 1.27 1.27)
					(thickness 0.15)
				)
			)
		)
		(property "Footprint" ""
			(at 373.38 127 0)
			(effects
				(font
					(size 1.27 1.27)
					(thickness 0.15)
				)
				(justify left bottom)
				(hide yes)
			)
		)
		(property "Datasheet" ""
			(at 373.38 132.08 0)
			(effects
				(font
					(size 1.27 1.27)
					(thickness 0.15)
				)
				(justify left bottom)
				(hide yes)
			)
		)
		(property "Description" ""
			(at 364.49 119.38 0)
			(effects
				(font
					(size 1.27 1.27)
				)
				(hide yes)
			)
		)
		(property "Author" "Antmicro"
			(at 373.38 127 0)
			(effects
				(font
					(size 1.27 1.27)
					(thickness 0.15)
				)
				(justify left bottom)
				(hide yes)
			)
		)
		(property "License" "Apache-2.0"
			(at 373.38 129.54 0)
			(effects
				(font
					(size 1.27 1.27)
					(thickness 0.15)
				)
				(justify left bottom)
				(hide yes)
			)
		)
		(pin "1"
		)
		(instances
			(project "thunderbolt-to-10gbe-adapter"
				(path ""
					(reference "#PWR0200")
					(unit 1)
				)
			)
		)
	)
	(symbol
		(lib_id "antmicropower:+5V")
		(at 217.17 60.96 0)
		(unit 1)
		(exclude_from_sim no)
		(in_bom yes)
		(on_board yes)
		(dnp no)
		(property "Reference" "#PWR0151"
			(at 232.41 63.5 0)
			(effects
				(font
					(size 1.27 1.27)
					(thickness 0.15)
				)
				(justify left bottom)
				(hide yes)
			)
		)
		(property "Value" "+5V"
			(at 217.17 57.15 0)
			(effects
				(font
					(size 1.27 1.27)
					(thickness 0.15)
				)
			)
		)
		(property "Footprint" ""
			(at 232.41 68.58 0)
			(effects
				(font
					(size 1.27 1.27)
					(thickness 0.15)
				)
				(justify left bottom)
				(hide yes)
			)
		)
		(property "Datasheet" ""
			(at 232.41 71.12 0)
			(effects
				(font
					(size 1.27 1.27)
					(thickness 0.15)
				)
				(justify left bottom)
				(hide yes)
			)
		)
		(property "Description" ""
			(at 232.41 73.66 0)
			(effects
				(font
					(size 1.27 1.27)
				)
				(justify left bottom)
				(hide yes)
			)
		)
		(property "Author" "Antmicro"
			(at 232.41 68.58 0)
			(effects
				(font
					(size 1.27 1.27)
					(thickness 0.15)
				)
				(justify left bottom)
				(hide yes)
			)
		)
		(property "License" "Apache-2.0"
			(at 232.41 71.12 0)
			(effects
				(font
					(size 1.27 1.27)
					(thickness 0.15)
				)
				(justify left bottom)
				(hide yes)
			)
		)
		(pin "1"
		)
		(instances
			(project "thunderbolt-to-10gbe-adapter"
				(path ""
					(reference "#PWR0151")
					(unit 1)
				)
			)
		)
	)
	(symbol
		(lib_id "antmicroCapacitors0402:C_33p_0402")
		(at 327.66 185.42 270)
		(mirror x)
		(unit 1)
		(exclude_from_sim no)
		(in_bom yes)
		(on_board yes)
		(dnp yes)
		(property "Reference" "C133"
			(at 325.882 181.61 90)
			(effects
				(font
					(size 1.27 1.27)
					(thickness 0.15)
				)
				(justify right)
			)
		)
		(property "Value" "C_33p_0402"
			(at 317.5 165.1 0)
			(effects
				(font
					(size 1.27 1.27)
					(thickness 0.15)
				)
				(justify left bottom)
				(hide yes)
			)
		)
		(property "Footprint" "antmicro-footprints:C_0402_1005Metric"
			(at 314.96 165.1 0)
			(effects
				(font
					(size 1.27 1.27)
					(thickness 0.15)
				)
				(justify left bottom)
				(hide yes)
			)
		)
		(property "Datasheet" "https://spicat.kyocera-avx.com/product/mlcc/chartview/04025A330FAT2A/"
			(at 312.42 165.1 0)
			(effects
				(font
					(size 1.27 1.27)
					(thickness 0.15)
				)
				(justify left bottom)
				(hide yes)
			)
		)
		(property "Description" "SMD Multilayer Ceramic Capacitor, 33 pF, 50 V, 0402 [1005 Metric], ± 5%, C0G / NP0, MC"
			(at 294.64 165.1 0)
			(effects
				(font
					(size 1.27 1.27)
				)
				(justify left bottom)
				(hide yes)
			)
		)
		(property "MPN" "04025A330FAT2A"
			(at 309.88 165.1 0)
			(effects
				(font
					(size 1.27 1.27)
					(thickness 0.15)
				)
				(justify left bottom)
				(hide yes)
			)
		)
		(property "Manufacturer" "KYOCERA AVX"
			(at 307.34 165.1 0)
			(effects
				(font
					(size 1.27 1.27)
					(thickness 0.15)
				)
				(justify left bottom)
				(hide yes)
			)
		)
		(property "License" "Apache-2.0"
			(at 304.8 165.1 0)
			(effects
				(font
					(size 1.27 1.27)
					(thickness 0.15)
				)
				(justify left bottom)
				(hide yes)
			)
		)
		(property "Author" "Antmicro"
			(at 302.26 165.1 0)
			(effects
				(font
					(size 1.27 1.27)
					(thickness 0.15)
				)
				(justify left bottom)
				(hide yes)
			)
		)
		(property "Val" "33p"
			(at 325.882 184.15 90)
			(effects
				(font
					(size 1.27 1.27)
					(thickness 0.15)
				)
				(justify right)
			)
		)
		(property "Voltage" ""
			(at 299.72 165.1 0)
			(effects
				(font
					(size 1.27 1.27)
				)
				(justify left bottom)
				(hide yes)
			)
		)
		(property "Dielectric" ""
			(at 297.18 165.1 0)
			(effects
				(font
					(size 1.27 1.27)
				)
				(justify left bottom)
				(hide yes)
			)
		)
		(pin "2"
		)
		(pin "1"
		)
		(instances
			(project "thunderbolt-to-10gbe-adapter"
				(path ""
					(reference "C133")
					(unit 1)
				)
			)
		)
	)
	(symbol
		(lib_id "antmicroCapacitors0402:C_100n_0402")
		(at 237.49 38.1 270)
		(mirror x)
		(unit 1)
		(exclude_from_sim no)
		(in_bom yes)
		(on_board yes)
		(dnp no)
		(property "Reference" "C114"
			(at 235.712 34.29 90)
			(effects
				(font
					(size 1.27 1.27)
					(thickness 0.15)
				)
				(justify right)
			)
		)
		(property "Value" "C_100n_0402"
			(at 227.33 17.78 0)
			(effects
				(font
					(size 1.27 1.27)
					(thickness 0.15)
				)
				(justify left bottom)
				(hide yes)
			)
		)
		(property "Footprint" "antmicro-footprints:C_0402_1005Metric"
			(at 224.79 17.78 0)
			(effects
				(font
					(size 1.27 1.27)
					(thickness 0.15)
				)
				(justify left bottom)
				(hide yes)
			)
		)
		(property "Datasheet" "https://www.murata.com/products/productdetail?partno=GRM155R61H104KE14%23"
			(at 222.25 17.78 0)
			(effects
				(font
					(size 1.27 1.27)
					(thickness 0.15)
				)
				(justify left bottom)
				(hide yes)
			)
		)
		(property "Description" "SMD Multilayer Ceramic Capacitor, 0.1 µF, 50 V, 0402 [1005 Metric], ± 10%, X5R, GRM Series"
			(at 204.47 17.78 0)
			(effects
				(font
					(size 1.27 1.27)
				)
				(justify left bottom)
				(hide yes)
			)
		)
		(property "MPN" "GRM155R61H104KE14D"
			(at 219.71 17.78 0)
			(effects
				(font
					(size 1.27 1.27)
					(thickness 0.15)
				)
				(justify left bottom)
				(hide yes)
			)
		)
		(property "Manufacturer" "Murata"
			(at 217.17 17.78 0)
			(effects
				(font
					(size 1.27 1.27)
					(thickness 0.15)
				)
				(justify left bottom)
				(hide yes)
			)
		)
		(property "License" "Apache-2.0"
			(at 214.63 17.78 0)
			(effects
				(font
					(size 1.27 1.27)
					(thickness 0.15)
				)
				(justify left bottom)
				(hide yes)
			)
		)
		(property "Author" "Antmicro"
			(at 212.09 17.78 0)
			(effects
				(font
					(size 1.27 1.27)
					(thickness 0.15)
				)
				(justify left bottom)
				(hide yes)
			)
		)
		(property "Val" "100n"
			(at 235.712 36.83 90)
			(effects
				(font
					(size 1.27 1.27)
					(thickness 0.15)
				)
				(justify right)
			)
		)
		(property "Voltage" "50V"
			(at 209.55 17.78 0)
			(effects
				(font
					(size 1.27 1.27)
				)
				(justify left bottom)
				(hide yes)
			)
		)
		(property "Dielectric" "X5R"
			(at 207.01 17.78 0)
			(effects
				(font
					(size 1.27 1.27)
				)
				(justify left bottom)
				(hide yes)
			)
		)
		(pin "1"
		)
		(pin "2"
		)
		(instances
			(project "thunderbolt-to-10gbe-adapter"
				(path ""
					(reference "C114")
					(unit 1)
				)
			)
		)
	)
	(symbol
		(lib_id "antmicropower:GND")
		(at 279.4 246.38 0)
		(mirror y)
		(unit 1)
		(exclude_from_sim no)
		(in_bom yes)
		(on_board yes)
		(dnp no)
		(property "Reference" "#PWR0176"
			(at 270.51 248.92 0)
			(effects
				(font
					(size 1.27 1.27)
					(thickness 0.15)
				)
				(justify left bottom)
				(hide yes)
			)
		)
		(property "Value" "GND"
			(at 279.4 250.19 0)
			(effects
				(font
					(size 1.27 1.27)
					(thickness 0.15)
				)
			)
		)
		(property "Footprint" ""
			(at 270.51 254 0)
			(effects
				(font
					(size 1.27 1.27)
					(thickness 0.15)
				)
				(justify left bottom)
				(hide yes)
			)
		)
		(property "Datasheet" ""
			(at 270.51 259.08 0)
			(effects
				(font
					(size 1.27 1.27)
					(thickness 0.15)
				)
				(justify left bottom)
				(hide yes)
			)
		)
		(property "Description" ""
			(at 279.4 246.38 0)
			(effects
				(font
					(size 1.27 1.27)
				)
				(hide yes)
			)
		)
		(property "Author" "Antmicro"
			(at 270.51 254 0)
			(effects
				(font
					(size 1.27 1.27)
					(thickness 0.15)
				)
				(justify left bottom)
				(hide yes)
			)
		)
		(property "License" "Apache-2.0"
			(at 270.51 256.54 0)
			(effects
				(font
					(size 1.27 1.27)
					(thickness 0.15)
				)
				(justify left bottom)
				(hide yes)
			)
		)
		(pin "1"
		)
		(instances
			(project "thunderbolt-to-10gbe-adapter"
				(path ""
					(reference "#PWR0176")
					(unit 1)
				)
			)
		)
	)
	(symbol
		(lib_id "antmicropower:GND")
		(at 332.74 195.58 0)
		(unit 1)
		(exclude_from_sim no)
		(in_bom yes)
		(on_board yes)
		(dnp no)
		(property "Reference" "#PWR0187"
			(at 341.63 198.12 0)
			(effects
				(font
					(size 1.27 1.27)
					(thickness 0.15)
				)
				(justify left bottom)
				(hide yes)
			)
		)
		(property "Value" "GND"
			(at 332.74 199.39 0)
			(effects
				(font
					(size 1.27 1.27)
					(thickness 0.15)
				)
			)
		)
		(property "Footprint" ""
			(at 341.63 203.2 0)
			(effects
				(font
					(size 1.27 1.27)
					(thickness 0.15)
				)
				(justify left bottom)
				(hide yes)
			)
		)
		(property "Datasheet" ""
			(at 341.63 208.28 0)
			(effects
				(font
					(size 1.27 1.27)
					(thickness 0.15)
				)
				(justify left bottom)
				(hide yes)
			)
		)
		(property "Description" ""
			(at 332.74 195.58 0)
			(effects
				(font
					(size 1.27 1.27)
				)
				(hide yes)
			)
		)
		(property "Author" "Antmicro"
			(at 341.63 203.2 0)
			(effects
				(font
					(size 1.27 1.27)
					(thickness 0.15)
				)
				(justify left bottom)
				(hide yes)
			)
		)
		(property "License" "Apache-2.0"
			(at 341.63 205.74 0)
			(effects
				(font
					(size 1.27 1.27)
					(thickness 0.15)
				)
				(justify left bottom)
				(hide yes)
			)
		)
		(pin "1"
		)
		(instances
			(project "thunderbolt-to-10gbe-adapter"
				(path ""
					(reference "#PWR0187")
					(unit 1)
				)
			)
		)
	)
	(symbol
		(lib_id "antmicropower:GND")
		(at 297.18 195.58 0)
		(unit 1)
		(exclude_from_sim no)
		(in_bom yes)
		(on_board yes)
		(dnp no)
		(property "Reference" "#PWR0181"
			(at 306.07 198.12 0)
			(effects
				(font
					(size 1.27 1.27)
					(thickness 0.15)
				)
				(justify left bottom)
				(hide yes)
			)
		)
		(property "Value" "GND"
			(at 297.18 199.39 0)
			(effects
				(font
					(size 1.27 1.27)
					(thickness 0.15)
				)
			)
		)
		(property "Footprint" ""
			(at 306.07 203.2 0)
			(effects
				(font
					(size 1.27 1.27)
					(thickness 0.15)
				)
				(justify left bottom)
				(hide yes)
			)
		)
		(property "Datasheet" ""
			(at 306.07 208.28 0)
			(effects
				(font
					(size 1.27 1.27)
					(thickness 0.15)
				)
				(justify left bottom)
				(hide yes)
			)
		)
		(property "Description" ""
			(at 297.18 195.58 0)
			(effects
				(font
					(size 1.27 1.27)
				)
				(hide yes)
			)
		)
		(property "Author" "Antmicro"
			(at 306.07 203.2 0)
			(effects
				(font
					(size 1.27 1.27)
					(thickness 0.15)
				)
				(justify left bottom)
				(hide yes)
			)
		)
		(property "License" "Apache-2.0"
			(at 306.07 205.74 0)
			(effects
				(font
					(size 1.27 1.27)
					(thickness 0.15)
				)
				(justify left bottom)
				(hide yes)
			)
		)
		(pin "1"
		)
		(instances
			(project "thunderbolt-to-10gbe-adapter"
				(path ""
					(reference "#PWR0181")
					(unit 1)
				)
			)
		)
	)
	(symbol
		(lib_id "antmicroResistors0402:R_16k_0402")
		(at 332.74 71.12 90)
		(unit 1)
		(exclude_from_sim no)
		(in_bom yes)
		(on_board yes)
		(dnp no)
		(property "Reference" "R100"
			(at 334.01 67.31 90)
			(effects
				(font
					(size 1.27 1.27)
					(thickness 0.15)
				)
				(justify right)
			)
		)
		(property "Value" "R_16k_0402"
			(at 345.44 50.8 0)
			(effects
				(font
					(size 1.27 1.27)
					(thickness 0.15)
				)
				(justify left bottom)
				(hide yes)
			)
		)
		(property "Footprint" "antmicro-footprints:R_0402_1005Metric"
			(at 347.98 50.8 0)
			(effects
				(font
					(size 1.27 1.27)
					(thickness 0.15)
				)
				(justify left bottom)
				(hide yes)
			)
		)
		(property "Datasheet" "https://www.bourns.com/docs/product-datasheets/cr.pdf"
			(at 350.52 50.8 0)
			(effects
				(font
					(size 1.27 1.27)
					(thickness 0.15)
				)
				(justify left bottom)
				(hide yes)
			)
		)
		(property "Description" "SMD Chip Resistor"
			(at 363.22 50.8 0)
			(effects
				(font
					(size 1.27 1.27)
				)
				(justify left bottom)
				(hide yes)
			)
		)
		(property "MPN" "CR0402-FX-1602GLF"
			(at 353.06 50.8 0)
			(effects
				(font
					(size 1.27 1.27)
					(thickness 0.15)
				)
				(justify left bottom)
				(hide yes)
			)
		)
		(property "Manufacturer" "Bourns"
			(at 355.6 50.8 0)
			(effects
				(font
					(size 1.27 1.27)
					(thickness 0.15)
				)
				(justify left bottom)
				(hide yes)
			)
		)
		(property "License" "Apache-2.0"
			(at 358.14 50.8 0)
			(effects
				(font
					(size 1.27 1.27)
					(thickness 0.15)
				)
				(justify left bottom)
				(hide yes)
			)
		)
		(property "Author" "Antmicro"
			(at 360.68 50.8 0)
			(effects
				(font
					(size 1.27 1.27)
					(thickness 0.15)
				)
				(justify left bottom)
				(hide yes)
			)
		)
		(property "Val" "16k"
			(at 334.01 69.85 90)
			(effects
				(font
					(size 1.27 1.27)
					(thickness 0.15)
				)
				(justify right)
			)
		)
		(property "Tolerance" "1%"
			(at 342.9 50.8 0)
			(effects
				(font
					(size 1.27 1.27)
				)
				(justify left bottom)
				(hide yes)
			)
		)
		(pin "2"
		)
		(pin "1"
		)
		(instances
			(project "thunderbolt-to-10gbe-adapter"
				(path ""
					(reference "R100")
					(unit 1)
				)
			)
		)
	)
	(symbol
		(lib_id "antmicroDCDCConverters:TPS566231P")
		(at 276.86 177.8 0)
		(unit 1)
		(exclude_from_sim no)
		(in_bom yes)
		(on_board yes)
		(dnp no)
		(fields_autoplaced yes)
		(property "Reference" "U13"
			(at 285.75 171.45 0)
			(effects
				(font
					(size 1.27 1.27)
					(thickness 0.15)
				)
			)
		)
		(property "Value" "TPS566231P"
			(at 309.88 182.88 0)
			(effects
				(font
					(size 1.27 1.27)
					(thickness 0.15)
				)
				(justify left bottom)
				(hide yes)
			)
		)
		(property "Footprint" "antmicro-footprints:VQFN-HR-9_2x1.5mm"
			(at 309.88 185.42 0)
			(effects
				(font
					(size 1.27 1.27)
					(thickness 0.15)
				)
				(justify left bottom)
				(hide yes)
			)
		)
		(property "Datasheet" "https://www.ti.com/lit/ds/symlink/tps566231.pdf"
			(at 309.88 187.96 0)
			(effects
				(font
					(size 1.27 1.27)
					(thickness 0.15)
				)
				(justify left bottom)
				(hide yes)
			)
		)
		(property "Description" "Switching Voltage Regulators 3-V to 18-V, 6-A synchronous buck converter"
			(at 309.88 200.66 0)
			(effects
				(font
					(size 1.27 1.27)
				)
				(justify left bottom)
				(hide yes)
			)
		)
		(property "Manufacturer" "Texas Instruments"
			(at 309.88 190.5 0)
			(effects
				(font
					(size 1.27 1.27)
					(thickness 0.15)
				)
				(justify left bottom)
				(hide yes)
			)
		)
		(property "MPN" "TPS566231PRQFR"
			(at 285.75 173.99 0)
			(effects
				(font
					(size 1.27 1.27)
					(thickness 0.15)
				)
			)
		)
		(property "Author" "Antmicro"
			(at 309.88 195.58 0)
			(effects
				(font
					(size 1.27 1.27)
					(thickness 0.15)
				)
				(justify left bottom)
				(hide yes)
			)
		)
		(property "License" "Apache-2.0"
			(at 309.88 198.12 0)
			(effects
				(font
					(size 1.27 1.27)
					(thickness 0.15)
				)
				(justify left bottom)
				(hide yes)
			)
		)
		(pin "1"
		)
		(pin "2"
		)
		(pin "3"
		)
		(pin "9"
		)
		(pin "5"
		)
		(pin "6"
		)
		(pin "8"
		)
		(pin "4"
		)
		(pin "7"
		)
		(instances
			(project "thunderbolt-to-10gbe-adapter"
				(path ""
					(reference "U13")
					(unit 1)
				)
			)
		)
	)
	(symbol
		(lib_id "antmicropower:GND")
		(at 217.17 157.48 0)
		(unit 1)
		(exclude_from_sim no)
		(in_bom yes)
		(on_board yes)
		(dnp no)
		(property "Reference" "#PWR0156"
			(at 226.06 160.02 0)
			(effects
				(font
					(size 1.27 1.27)
					(thickness 0.15)
				)
				(justify left bottom)
				(hide yes)
			)
		)
		(property "Value" "GND"
			(at 217.17 161.29 0)
			(effects
				(font
					(size 1.27 1.27)
					(thickness 0.15)
				)
			)
		)
		(property "Footprint" ""
			(at 226.06 165.1 0)
			(effects
				(font
					(size 1.27 1.27)
					(thickness 0.15)
				)
				(justify left bottom)
				(hide yes)
			)
		)
		(property "Datasheet" ""
			(at 226.06 170.18 0)
			(effects
				(font
					(size 1.27 1.27)
					(thickness 0.15)
				)
				(justify left bottom)
				(hide yes)
			)
		)
		(property "Description" ""
			(at 217.17 157.48 0)
			(effects
				(font
					(size 1.27 1.27)
				)
				(hide yes)
			)
		)
		(property "Author" "Antmicro"
			(at 226.06 165.1 0)
			(effects
				(font
					(size 1.27 1.27)
					(thickness 0.15)
				)
				(justify left bottom)
				(hide yes)
			)
		)
		(property "License" "Apache-2.0"
			(at 226.06 167.64 0)
			(effects
				(font
					(size 1.27 1.27)
					(thickness 0.15)
				)
				(justify left bottom)
				(hide yes)
			)
		)
		(pin "1"
		)
		(instances
			(project "thunderbolt-to-10gbe-adapter"
				(path ""
					(reference "#PWR0156")
					(unit 1)
				)
			)
		)
	)
	(symbol
		(lib_id "antmicroCapacitors0603:C_22u_16V_0603")
		(at 227.33 152.4 270)
		(mirror x)
		(unit 1)
		(exclude_from_sim no)
		(in_bom yes)
		(on_board yes)
		(dnp no)
		(property "Reference" "C112"
			(at 225.552 148.59 90)
			(effects
				(font
					(size 1.27 1.27)
					(thickness 0.15)
				)
				(justify right)
			)
		)
		(property "Value" "C_22u_16V_0603"
			(at 217.17 132.08 0)
			(effects
				(font
					(size 1.27 1.27)
					(thickness 0.15)
				)
				(justify left bottom)
				(hide yes)
			)
		)
		(property "Footprint" "antmicro-footprints:C_0603_1608Metric_EIA"
			(at 214.63 132.08 0)
			(effects
				(font
					(size 1.27 1.27)
					(thickness 0.15)
				)
				(justify left bottom)
				(hide yes)
			)
		)
		(property "Datasheet" "https://product.samsungsem.com/mlcc/CL10A226MO7JZN.do"
			(at 212.09 132.08 0)
			(effects
				(font
					(size 1.27 1.27)
					(thickness 0.15)
				)
				(justify left bottom)
				(hide yes)
			)
		)
		(property "Description" "SMD Multilayer Ceramic Capacitor"
			(at 227.33 152.4 0)
			(effects
				(font
					(size 1.27 1.27)
				)
				(hide yes)
			)
		)
		(property "MPN" "CL10A226MO7JZNC"
			(at 209.55 132.08 0)
			(effects
				(font
					(size 1.27 1.27)
					(thickness 0.15)
				)
				(justify left bottom)
				(hide yes)
			)
		)
		(property "Manufacturer" "Samsung Electro-Mechanics"
			(at 207.01 132.08 0)
			(effects
				(font
					(size 1.27 1.27)
					(thickness 0.15)
				)
				(justify left bottom)
				(hide yes)
			)
		)
		(property "License" "Apache-2.0"
			(at 204.47 132.08 0)
			(effects
				(font
					(size 1.27 1.27)
					(thickness 0.15)
				)
				(justify left bottom)
				(hide yes)
			)
		)
		(property "Author" "Antmicro"
			(at 201.93 132.08 0)
			(effects
				(font
					(size 1.27 1.27)
					(thickness 0.15)
				)
				(justify left bottom)
				(hide yes)
			)
		)
		(property "Val" "22u"
			(at 225.552 151.13 90)
			(effects
				(font
					(size 1.27 1.27)
					(thickness 0.15)
				)
				(justify right)
			)
		)
		(property "Voltage" "16V"
			(at 224.79 152.3935 90)
			(effects
				(font
					(size 1.27 1.27)
				)
				(justify right)
				(hide yes)
			)
		)
		(property "Dielectric" ""
			(at 196.85 132.08 0)
			(effects
				(font
					(size 1.27 1.27)
				)
				(justify left bottom)
				(hide yes)
			)
		)
		(pin "2"
		)
		(pin "1"
		)
		(instances
			(project "thunderbolt-to-10gbe-adapter"
				(path ""
					(reference "C112")
					(unit 1)
				)
			)
		)
	)
	(symbol
		(lib_id "antmicropower:GND")
		(at 227.33 195.58 0)
		(unit 1)
		(exclude_from_sim no)
		(in_bom yes)
		(on_board yes)
		(dnp no)
		(property "Reference" "#PWR0163"
			(at 236.22 198.12 0)
			(effects
				(font
					(size 1.27 1.27)
					(thickness 0.15)
				)
				(justify left bottom)
				(hide yes)
			)
		)
		(property "Value" "GND"
			(at 227.33 199.39 0)
			(effects
				(font
					(size 1.27 1.27)
					(thickness 0.15)
				)
			)
		)
		(property "Footprint" ""
			(at 236.22 203.2 0)
			(effects
				(font
					(size 1.27 1.27)
					(thickness 0.15)
				)
				(justify left bottom)
				(hide yes)
			)
		)
		(property "Datasheet" ""
			(at 236.22 208.28 0)
			(effects
				(font
					(size 1.27 1.27)
					(thickness 0.15)
				)
				(justify left bottom)
				(hide yes)
			)
		)
		(property "Description" ""
			(at 227.33 195.58 0)
			(effects
				(font
					(size 1.27 1.27)
				)
				(hide yes)
			)
		)
		(property "Author" "Antmicro"
			(at 236.22 203.2 0)
			(effects
				(font
					(size 1.27 1.27)
					(thickness 0.15)
				)
				(justify left bottom)
				(hide yes)
			)
		)
		(property "License" "Apache-2.0"
			(at 236.22 205.74 0)
			(effects
				(font
					(size 1.27 1.27)
					(thickness 0.15)
				)
				(justify left bottom)
				(hide yes)
			)
		)
		(pin "1"
		)
		(instances
			(project "thunderbolt-to-10gbe-adapter"
				(path ""
					(reference "#PWR0163")
					(unit 1)
				)
			)
		)
	)
	(symbol
		(lib_id "antmicroCapacitors0402:C_33p_0402")
		(at 327.66 71.12 270)
		(mirror x)
		(unit 1)
		(exclude_from_sim no)
		(in_bom yes)
		(on_board yes)
		(dnp yes)
		(property "Reference" "C130"
			(at 325.882 67.31 90)
			(effects
				(font
					(size 1.27 1.27)
					(thickness 0.15)
				)
				(justify right)
			)
		)
		(property "Value" "C_33p_0402"
			(at 317.5 50.8 0)
			(effects
				(font
					(size 1.27 1.27)
					(thickness 0.15)
				)
				(justify left bottom)
				(hide yes)
			)
		)
		(property "Footprint" "antmicro-footprints:C_0402_1005Metric"
			(at 314.96 50.8 0)
			(effects
				(font
					(size 1.27 1.27)
					(thickness 0.15)
				)
				(justify left bottom)
				(hide yes)
			)
		)
		(property "Datasheet" "https://spicat.kyocera-avx.com/product/mlcc/chartview/04025A330FAT2A/"
			(at 312.42 50.8 0)
			(effects
				(font
					(size 1.27 1.27)
					(thickness 0.15)
				)
				(justify left bottom)
				(hide yes)
			)
		)
		(property "Description" "SMD Multilayer Ceramic Capacitor, 33 pF, 50 V, 0402 [1005 Metric], ± 5%, C0G / NP0, MC"
			(at 294.64 50.8 0)
			(effects
				(font
					(size 1.27 1.27)
				)
				(justify left bottom)
				(hide yes)
			)
		)
		(property "MPN" "04025A330FAT2A"
			(at 309.88 50.8 0)
			(effects
				(font
					(size 1.27 1.27)
					(thickness 0.15)
				)
				(justify left bottom)
				(hide yes)
			)
		)
		(property "Manufacturer" "KYOCERA AVX"
			(at 307.34 50.8 0)
			(effects
				(font
					(size 1.27 1.27)
					(thickness 0.15)
				)
				(justify left bottom)
				(hide yes)
			)
		)
		(property "License" "Apache-2.0"
			(at 304.8 50.8 0)
			(effects
				(font
					(size 1.27 1.27)
					(thickness 0.15)
				)
				(justify left bottom)
				(hide yes)
			)
		)
		(property "Author" "Antmicro"
			(at 302.26 50.8 0)
			(effects
				(font
					(size 1.27 1.27)
					(thickness 0.15)
				)
				(justify left bottom)
				(hide yes)
			)
		)
		(property "Val" "33p"
			(at 325.882 69.85 90)
			(effects
				(font
					(size 1.27 1.27)
					(thickness 0.15)
				)
				(justify right)
			)
		)
		(property "Voltage" ""
			(at 299.72 50.8 0)
			(effects
				(font
					(size 1.27 1.27)
				)
				(justify left bottom)
				(hide yes)
			)
		)
		(property "Dielectric" ""
			(at 297.18 50.8 0)
			(effects
				(font
					(size 1.27 1.27)
				)
				(justify left bottom)
				(hide yes)
			)
		)
		(pin "2"
		)
		(pin "1"
		)
		(instances
			(project "thunderbolt-to-10gbe-adapter"
				(path ""
					(reference "C130")
					(unit 1)
				)
			)
		)
	)
	(symbol
		(lib_id "antmicroResistors0402:R_330R_0402")
		(at 279.4 231.14 90)
		(unit 1)
		(exclude_from_sim no)
		(in_bom yes)
		(on_board yes)
		(dnp no)
		(property "Reference" "R96"
			(at 280.67 227.33 90)
			(effects
				(font
					(size 1.27 1.27)
					(thickness 0.15)
				)
				(justify right)
			)
		)
		(property "Value" "R_330R_0402"
			(at 292.1 210.82 0)
			(effects
				(font
					(size 1.27 1.27)
					(thickness 0.15)
				)
				(justify left bottom)
				(hide yes)
			)
		)
		(property "Footprint" "antmicro-footprints:R_0402_1005Metric"
			(at 294.64 210.82 0)
			(effects
				(font
					(size 1.27 1.27)
					(thickness 0.15)
				)
				(justify left bottom)
				(hide yes)
			)
		)
		(property "Datasheet" "https://www.bourns.com/docs/product-datasheets/cr.pdf"
			(at 297.18 210.82 0)
			(effects
				(font
					(size 1.27 1.27)
					(thickness 0.15)
				)
				(justify left bottom)
				(hide yes)
			)
		)
		(property "Description" "SMD Chip Resistor, 330 ohm, ± 1%, 62.5 mW, 0402 [1005 Metric], Thick Film, General Purpose"
			(at 309.88 210.82 0)
			(effects
				(font
					(size 1.27 1.27)
				)
				(justify left bottom)
				(hide yes)
			)
		)
		(property "MPN" "CR0402-FX-3300GLF"
			(at 299.72 210.82 0)
			(effects
				(font
					(size 1.27 1.27)
					(thickness 0.15)
				)
				(justify left bottom)
				(hide yes)
			)
		)
		(property "Manufacturer" "Bourns"
			(at 302.26 210.82 0)
			(effects
				(font
					(size 1.27 1.27)
					(thickness 0.15)
				)
				(justify left bottom)
				(hide yes)
			)
		)
		(property "License" "Apache-2.0"
			(at 304.8 210.82 0)
			(effects
				(font
					(size 1.27 1.27)
					(thickness 0.15)
				)
				(justify left bottom)
				(hide yes)
			)
		)
		(property "Author" "Antmicro"
			(at 307.34 210.82 0)
			(effects
				(font
					(size 1.27 1.27)
					(thickness 0.15)
				)
				(justify left bottom)
				(hide yes)
			)
		)
		(property "Val" "330R"
			(at 280.67 229.87 90)
			(effects
				(font
					(size 1.27 1.27)
					(thickness 0.15)
				)
				(justify right)
			)
		)
		(property "Tolerance" "1%"
			(at 289.56 210.82 0)
			(effects
				(font
					(size 1.27 1.27)
				)
				(justify left bottom)
				(hide yes)
			)
		)
		(pin "2"
		)
		(pin "1"
		)
		(instances
			(project "thunderbolt-to-10gbe-adapter"
				(path ""
					(reference "R96")
					(unit 1)
				)
			)
		)
	)
	(symbol
		(lib_id "antmicroCapacitors0402:C_100n_0402")
		(at 307.34 182.88 270)
		(mirror x)
		(unit 1)
		(exclude_from_sim no)
		(in_bom yes)
		(on_board yes)
		(dnp no)
		(property "Reference" "C128"
			(at 309.118 179.324 90)
			(effects
				(font
					(size 1.27 1.27)
					(thickness 0.15)
				)
				(justify left)
			)
		)
		(property "Value" "C_100n_0402"
			(at 297.18 162.56 0)
			(effects
				(font
					(size 1.27 1.27)
					(thickness 0.15)
				)
				(justify left bottom)
				(hide yes)
			)
		)
		(property "Footprint" "antmicro-footprints:C_0402_1005Metric"
			(at 294.64 162.56 0)
			(effects
				(font
					(size 1.27 1.27)
					(thickness 0.15)
				)
				(justify left bottom)
				(hide yes)
			)
		)
		(property "Datasheet" "https://www.murata.com/products/productdetail?partno=GRM155R61H104KE14%23"
			(at 292.1 162.56 0)
			(effects
				(font
					(size 1.27 1.27)
					(thickness 0.15)
				)
				(justify left bottom)
				(hide yes)
			)
		)
		(property "Description" "SMD Multilayer Ceramic Capacitor, 0.1 µF, 50 V, 0402 [1005 Metric], ± 10%, X5R, GRM Series"
			(at 274.32 162.56 0)
			(effects
				(font
					(size 1.27 1.27)
				)
				(justify left bottom)
				(hide yes)
			)
		)
		(property "MPN" "GRM155R61H104KE14D"
			(at 289.56 162.56 0)
			(effects
				(font
					(size 1.27 1.27)
					(thickness 0.15)
				)
				(justify left bottom)
				(hide yes)
			)
		)
		(property "Manufacturer" "Murata"
			(at 287.02 162.56 0)
			(effects
				(font
					(size 1.27 1.27)
					(thickness 0.15)
				)
				(justify left bottom)
				(hide yes)
			)
		)
		(property "License" "Apache-2.0"
			(at 284.48 162.56 0)
			(effects
				(font
					(size 1.27 1.27)
					(thickness 0.15)
				)
				(justify left bottom)
				(hide yes)
			)
		)
		(property "Author" "Antmicro"
			(at 281.94 162.56 0)
			(effects
				(font
					(size 1.27 1.27)
					(thickness 0.15)
				)
				(justify left bottom)
				(hide yes)
			)
		)
		(property "Val" "100n"
			(at 309.118 181.864 90)
			(effects
				(font
					(size 1.27 1.27)
					(thickness 0.15)
				)
				(justify left)
			)
		)
		(property "Voltage" "50V"
			(at 279.4 162.56 0)
			(effects
				(font
					(size 1.27 1.27)
				)
				(justify left bottom)
				(hide yes)
			)
		)
		(property "Dielectric" "X5R"
			(at 276.86 162.56 0)
			(effects
				(font
					(size 1.27 1.27)
				)
				(justify left bottom)
				(hide yes)
			)
		)
		(pin "1"
		)
		(pin "2"
		)
		(instances
			(project "thunderbolt-to-10gbe-adapter"
				(path ""
					(reference "C128")
					(unit 1)
				)
			)
		)
	)
	(symbol
		(lib_id "antmicroCapacitors0603:C_22u_16V_0603")
		(at 217.17 76.2 270)
		(mirror x)
		(unit 1)
		(exclude_from_sim no)
		(in_bom yes)
		(on_board yes)
		(dnp no)
		(property "Reference" "C105"
			(at 215.138 72.39 90)
			(effects
				(font
					(size 1.27 1.27)
					(thickness 0.15)
				)
				(justify right)
			)
		)
		(property "Value" "C_22u_16V_0603"
			(at 207.01 55.88 0)
			(effects
				(font
					(size 1.27 1.27)
					(thickness 0.15)
				)
				(justify left bottom)
				(hide yes)
			)
		)
		(property "Footprint" "antmicro-footprints:C_0603_1608Metric_EIA"
			(at 204.47 55.88 0)
			(effects
				(font
					(size 1.27 1.27)
					(thickness 0.15)
				)
				(justify left bottom)
				(hide yes)
			)
		)
		(property "Datasheet" "https://product.samsungsem.com/mlcc/CL10A226MO7JZN.do"
			(at 201.93 55.88 0)
			(effects
				(font
					(size 1.27 1.27)
					(thickness 0.15)
				)
				(justify left bottom)
				(hide yes)
			)
		)
		(property "Description" "SMD Multilayer Ceramic Capacitor"
			(at 217.17 76.2 0)
			(effects
				(font
					(size 1.27 1.27)
				)
				(hide yes)
			)
		)
		(property "MPN" "CL10A226MO7JZNC"
			(at 199.39 55.88 0)
			(effects
				(font
					(size 1.27 1.27)
					(thickness 0.15)
				)
				(justify left bottom)
				(hide yes)
			)
		)
		(property "Manufacturer" "Samsung Electro-Mechanics"
			(at 196.85 55.88 0)
			(effects
				(font
					(size 1.27 1.27)
					(thickness 0.15)
				)
				(justify left bottom)
				(hide yes)
			)
		)
		(property "License" "Apache-2.0"
			(at 194.31 55.88 0)
			(effects
				(font
					(size 1.27 1.27)
					(thickness 0.15)
				)
				(justify left bottom)
				(hide yes)
			)
		)
		(property "Author" "Antmicro"
			(at 191.77 55.88 0)
			(effects
				(font
					(size 1.27 1.27)
					(thickness 0.15)
				)
				(justify left bottom)
				(hide yes)
			)
		)
		(property "Val" "22u"
			(at 215.138 74.93 90)
			(effects
				(font
					(size 1.27 1.27)
					(thickness 0.15)
				)
				(justify right)
			)
		)
		(property "Voltage" "16V"
			(at 214.63 76.1935 90)
			(effects
				(font
					(size 1.27 1.27)
				)
				(justify right)
				(hide yes)
			)
		)
		(property "Dielectric" ""
			(at 186.69 55.88 0)
			(effects
				(font
					(size 1.27 1.27)
				)
				(justify left bottom)
				(hide yes)
			)
		)
		(pin "2"
		)
		(pin "1"
		)
		(instances
			(project "thunderbolt-to-10gbe-adapter"
				(path ""
					(reference "C105")
					(unit 1)
				)
			)
		)
	)
	(symbol
		(lib_id "antmicroTransistorsFETsMOSFETsSingle:2N7002_SOT-23-3")
		(at 312.42 240.03 0)
		(mirror y)
		(unit 1)
		(exclude_from_sim no)
		(in_bom yes)
		(on_board yes)
		(dnp no)
		(property "Reference" "Q6"
			(at 302.26 236.22 0)
			(effects
				(font
					(size 1.27 1.27)
					(thickness 0.15)
				)
				(justify left)
			)
		)
		(property "Value" "2N7002_SOT-23-3"
			(at 289.56 247.65 0)
			(effects
				(font
					(size 1.27 1.27)
					(thickness 0.15)
				)
				(justify left bottom)
				(hide yes)
			)
		)
		(property "Footprint" "antmicro-footprints:SOT-23-3"
			(at 289.56 250.19 0)
			(effects
				(font
					(size 1.27 1.27)
					(thickness 0.15)
				)
				(justify left bottom)
				(hide yes)
			)
		)
		(property "Datasheet" "https://www.onsemi.com/pub/Collateral/NDS7002A-D.PDF"
			(at 289.56 252.73 0)
			(effects
				(font
					(size 1.27 1.27)
					(thickness 0.15)
				)
				(justify left bottom)
				(hide yes)
			)
		)
		(property "Description" "Power MOSFET, N Channel, 60 V, 115 mA, 1.2 ohm, SOT-23, Surface Mount"
			(at 289.56 265.43 0)
			(effects
				(font
					(size 1.27 1.27)
				)
				(justify left bottom)
				(hide yes)
			)
		)
		(property "MPN" "2N7002"
			(at 302.26 238.76 0)
			(effects
				(font
					(size 1.27 1.27)
					(thickness 0.15)
				)
				(justify left)
			)
		)
		(property "Manufacturer" "ON Semiconductor"
			(at 289.56 257.81 0)
			(effects
				(font
					(size 1.27 1.27)
					(thickness 0.15)
				)
				(justify left bottom)
				(hide yes)
			)
		)
		(property "Author" "Antmicro"
			(at 289.56 260.35 0)
			(effects
				(font
					(size 1.27 1.27)
					(thickness 0.15)
				)
				(justify left bottom)
				(hide yes)
			)
		)
		(property "License" "Apache-2.0"
			(at 289.56 262.89 0)
			(effects
				(font
					(size 1.27 1.27)
					(thickness 0.15)
				)
				(justify left bottom)
				(hide yes)
			)
		)
		(pin "3"
		)
		(pin "2"
		)
		(pin "1"
		)
		(instances
			(project "thunderbolt-to-10gbe-adapter"
				(path ""
					(reference "Q6")
					(unit 1)
				)
			)
		)
	)
	(symbol
		(lib_id "antmicroResistors0402:R_0R_0402")
		(at 261.62 73.66 0)
		(unit 1)
		(exclude_from_sim no)
		(in_bom yes)
		(on_board yes)
		(dnp no)
		(property "Reference" "R92"
			(at 264.16 71.374 0)
			(effects
				(font
					(size 1.27 1.27)
					(thickness 0.15)
				)
			)
		)
		(property "Value" "R_0R_0402"
			(at 281.94 86.36 0)
			(effects
				(font
					(size 1.27 1.27)
					(thickness 0.15)
				)
				(justify left bottom)
				(hide yes)
			)
		)
		(property "Footprint" "antmicro-footprints:R_0402_1005Metric"
			(at 281.94 88.9 0)
			(effects
				(font
					(size 1.27 1.27)
					(thickness 0.15)
				)
				(justify left bottom)
				(hide yes)
			)
		)
		(property "Datasheet" "https://industrial.panasonic.com/cdbs/www-data/pdf/RDA0000/AOA0000C301.pdf"
			(at 281.94 91.44 0)
			(effects
				(font
					(size 1.27 1.27)
					(thickness 0.15)
				)
				(justify left bottom)
				(hide yes)
			)
		)
		(property "Description" "SMD Chip Resistor, Jumper, 0 ohm, 100 mW, 0402 [1005 Metric], Thick Film, General Purpose"
			(at 281.94 106.68 0)
			(effects
				(font
					(size 1.27 1.27)
				)
				(justify left bottom)
				(hide yes)
			)
		)
		(property "MPN" "ERJ2GE0R00X"
			(at 281.94 93.98 0)
			(effects
				(font
					(size 1.27 1.27)
					(thickness 0.15)
				)
				(justify left bottom)
				(hide yes)
			)
		)
		(property "Manufacturer" "Panasonic"
			(at 281.94 96.52 0)
			(effects
				(font
					(size 1.27 1.27)
					(thickness 0.15)
				)
				(justify left bottom)
				(hide yes)
			)
		)
		(property "License" "Apache-2.0"
			(at 281.94 99.06 0)
			(effects
				(font
					(size 1.27 1.27)
					(thickness 0.15)
				)
				(justify left bottom)
				(hide yes)
			)
		)
		(property "Author" "Antmicro"
			(at 281.94 101.6 0)
			(effects
				(font
					(size 1.27 1.27)
					(thickness 0.15)
				)
				(justify left bottom)
				(hide yes)
			)
		)
		(property "Val" "0R"
			(at 264.16 75.946 0)
			(effects
				(font
					(size 1.27 1.27)
					(thickness 0.15)
				)
			)
		)
		(property "Tolerance" "~"
			(at 281.94 83.82 0)
			(effects
				(font
					(size 1.27 1.27)
				)
				(justify left bottom)
				(hide yes)
			)
		)
		(property "Current" "1A"
			(at 281.94 104.14 0)
			(effects
				(font
					(size 1.27 1.27)
					(thickness 0.15)
				)
				(justify left bottom)
				(hide yes)
			)
		)
		(pin "2"
		)
		(pin "1"
		)
		(instances
			(project "thunderbolt-to-10gbe-adapter"
				(path ""
					(reference "R92")
					(unit 1)
				)
			)
		)
	)
	(symbol
		(lib_id "antmicropower:+5V")
		(at 217.17 175.26 0)
		(unit 1)
		(exclude_from_sim no)
		(in_bom yes)
		(on_board yes)
		(dnp no)
		(property "Reference" "#PWR0157"
			(at 232.41 177.8 0)
			(effects
				(font
					(size 1.27 1.27)
					(thickness 0.15)
				)
				(justify left bottom)
				(hide yes)
			)
		)
		(property "Value" "+5V"
			(at 217.17 171.45 0)
			(effects
				(font
					(size 1.27 1.27)
					(thickness 0.15)
				)
			)
		)
		(property "Footprint" ""
			(at 232.41 182.88 0)
			(effects
				(font
					(size 1.27 1.27)
					(thickness 0.15)
				)
				(justify left bottom)
				(hide yes)
			)
		)
		(property "Datasheet" ""
			(at 232.41 185.42 0)
			(effects
				(font
					(size 1.27 1.27)
					(thickness 0.15)
				)
				(justify left bottom)
				(hide yes)
			)
		)
		(property "Description" ""
			(at 232.41 187.96 0)
			(effects
				(font
					(size 1.27 1.27)
				)
				(justify left bottom)
				(hide yes)
			)
		)
		(property "Author" "Antmicro"
			(at 232.41 182.88 0)
			(effects
				(font
					(size 1.27 1.27)
					(thickness 0.15)
				)
				(justify left bottom)
				(hide yes)
			)
		)
		(property "License" "Apache-2.0"
			(at 232.41 185.42 0)
			(effects
				(font
					(size 1.27 1.27)
					(thickness 0.15)
				)
				(justify left bottom)
				(hide yes)
			)
		)
		(pin "1"
		)
		(instances
			(project "thunderbolt-to-10gbe-adapter"
				(path ""
					(reference "#PWR0157")
					(unit 1)
				)
			)
		)
	)
	(symbol
		(lib_id "antmicropower:VCC")
		(at 387.35 231.14 90)
		(unit 1)
		(exclude_from_sim no)
		(in_bom yes)
		(on_board yes)
		(dnp no)
		(fields_autoplaced yes)
		(property "Reference" "#PWR0209"
			(at 391.16 231.14 0)
			(effects
				(font
					(size 1.27 1.27)
				)
				(hide yes)
			)
		)
		(property "Value" "VCCD"
			(at 383.54 231.1399 90)
			(effects
				(font
					(size 1.27 1.27)
				)
				(justify left)
			)
		)
		(property "Footprint" ""
			(at 387.35 231.14 0)
			(effects
				(font
					(size 1.27 1.27)
				)
				(hide yes)
			)
		)
		(property "Datasheet" ""
			(at 387.35 231.14 0)
			(effects
				(font
					(size 1.27 1.27)
				)
				(hide yes)
			)
		)
		(property "Description" ""
			(at 387.35 231.14 0)
			(effects
				(font
					(size 1.27 1.27)
				)
				(hide yes)
			)
		)
		(pin "1"
		)
		(instances
			(project "thunderbolt-to-10gbe-adapter"
				(path ""
					(reference "#PWR0209")
					(unit 1)
				)
			)
		)
	)
	(symbol
		(lib_id "antmicropower:+1V8")
		(at 400.05 99.06 0)
		(unit 1)
		(exclude_from_sim no)
		(in_bom yes)
		(on_board yes)
		(dnp no)
		(property "Reference" "#PWR0215"
			(at 415.29 101.6 0)
			(effects
				(font
					(size 1.27 1.27)
					(thickness 0.15)
				)
				(justify left bottom)
				(hide yes)
			)
		)
		(property "Value" "+1V88"
			(at 400.05 95.25 0)
			(effects
				(font
					(size 1.27 1.27)
					(thickness 0.15)
				)
			)
		)
		(property "Footprint" ""
			(at 415.29 106.68 0)
			(effects
				(font
					(size 1.27 1.27)
					(thickness 0.15)
				)
				(justify left bottom)
				(hide yes)
			)
		)
		(property "Datasheet" ""
			(at 415.29 109.22 0)
			(effects
				(font
					(size 1.27 1.27)
					(thickness 0.15)
				)
				(justify left bottom)
				(hide yes)
			)
		)
		(property "Description" ""
			(at 400.05 99.06 0)
			(effects
				(font
					(size 1.27 1.27)
				)
				(hide yes)
			)
		)
		(property "Author" "Antmicro"
			(at 415.29 104.14 0)
			(effects
				(font
					(size 1.27 1.27)
					(thickness 0.15)
				)
				(justify left bottom)
				(hide yes)
			)
		)
		(property "License" "Apache-2.0"
			(at 415.29 106.68 0)
			(effects
				(font
					(size 1.27 1.27)
					(thickness 0.15)
				)
				(justify left bottom)
				(hide yes)
			)
		)
		(pin "1"
		)
		(instances
			(project "thunderbolt-to-10gbe-adapter"
				(path ""
					(reference "#PWR0215")
					(unit 1)
				)
			)
		)
	)
	(symbol
		(lib_id "antmicroTestPoints:TP_0.75mm_SMD")
		(at 391.16 238.76 0)
		(unit 1)
		(exclude_from_sim no)
		(in_bom no)
		(on_board yes)
		(dnp no)
		(fields_autoplaced yes)
		(property "Reference" "TP19"
			(at 396.24 238.76 0)
			(effects
				(font
					(size 1.27 1.27)
					(thickness 0.15)
				)
				(justify left)
			)
		)
		(property "Value" "TP_0.75mm_SMD"
			(at 401.32 242.57 0)
			(effects
				(font
					(size 1.27 1.27)
					(thickness 0.15)
				)
				(justify left bottom)
				(hide yes)
			)
		)
		(property "Footprint" "antmicro-footprints:TP_SMD_0.75mm"
			(at 401.32 245.11 0)
			(effects
				(font
					(size 1.27 1.27)
					(thickness 0.15)
				)
				(justify left bottom)
				(hide yes)
			)
		)
		(property "Datasheet" ""
			(at 408.94 251.46 0)
			(effects
				(font
					(size 1.27 1.27)
					(thickness 0.15)
				)
				(justify left bottom)
				(hide yes)
			)
		)
		(property "Description" "SMT test point"
			(at 401.955 252.73 0)
			(effects
				(font
					(size 1.27 1.27)
				)
				(justify left bottom)
				(hide yes)
			)
		)
		(property "MPN" ""
			(at 401.955 250.19 0)
			(effects
				(font
					(size 1.27 1.27)
					(thickness 0.15)
				)
				(justify left bottom)
				(hide yes)
			)
		)
		(property "Manufacturer" ""
			(at 401.955 245.11 0)
			(effects
				(font
					(size 1.27 1.27)
					(thickness 0.15)
				)
				(justify left bottom)
				(hide yes)
			)
		)
		(property "Author" "Antmicro"
			(at 401.32 247.65 0)
			(effects
				(font
					(size 1.27 1.27)
					(thickness 0.15)
				)
				(justify left bottom)
				(hide yes)
			)
		)
		(property "License" "Apache-2.0"
			(at 401.32 250.19 0)
			(effects
				(font
					(size 1.27 1.27)
					(thickness 0.15)
				)
				(justify left bottom)
				(hide yes)
			)
		)
		(pin "1"
		)
		(instances
			(project "thunderbolt-to-10gbe-adapter"
				(path ""
					(reference "TP19")
					(unit 1)
				)
			)
		)
	)
	(symbol
		(lib_id "antmicroFixedInductors:L_1u_10A_Bourns-SRP4021HMT")
		(at 314.96 139.7 0)
		(unit 1)
		(exclude_from_sim no)
		(in_bom yes)
		(on_board yes)
		(dnp no)
		(fields_autoplaced yes)
		(property "Reference" "L7"
			(at 317.5 134.62 0)
			(effects
				(font
					(size 1.27 1.27)
					(thickness 0.15)
				)
			)
		)
		(property "Value" "L_1u_10A_Bourns-SRP4021HMT"
			(at 330.2 149.86 0)
			(effects
				(font
					(size 1.27 1.27)
					(thickness 0.15)
				)
				(justify left bottom)
				(hide yes)
			)
		)
		(property "Footprint" "antmicro-footprints:L_Bourns-SRP4021HMT"
			(at 330.2 152.4 0)
			(effects
				(font
					(size 1.27 1.27)
					(thickness 0.15)
				)
				(justify left bottom)
				(hide yes)
			)
		)
		(property "Datasheet" "https://www.mouser.com/datasheet/2/54/Bourns_04_01_2025_SRP4021HMT_Datasheet-3580094.pdf"
			(at 330.2 154.94 0)
			(effects
				(font
					(size 1.27 1.27)
					(thickness 0.15)
				)
				(justify left bottom)
				(hide yes)
			)
		)
		(property "Description" "Power Inductors - SMD Ind,4.1x4.2x1.9mm,1uH+/-20%,10A, Shielded"
			(at 330.2 157.48 0)
			(effects
				(font
					(size 1.27 1.27)
					(thickness 0.15)
				)
				(justify left bottom)
				(hide yes)
			)
		)
		(property "Val" "1u/10A"
			(at 317.5 137.16 0)
			(effects
				(font
					(size 1.27 1.27)
					(thickness 0.15)
				)
			)
		)
		(property "Manufacturer" "Bourns"
			(at 330.2 160.02 0)
			(effects
				(font
					(size 1.27 1.27)
					(thickness 0.15)
				)
				(justify left bottom)
				(hide yes)
			)
		)
		(property "MPN" "SRP4021HMT-1R0M"
			(at 330.2 162.56 0)
			(effects
				(font
					(size 1.27 1.27)
					(thickness 0.15)
				)
				(justify left bottom)
				(hide yes)
			)
		)
		(property "ISat" ""
			(at 328.93 156.21 0)
			(effects
				(font
					(size 1.27 1.27)
				)
				(justify left)
				(hide yes)
			)
		)
		(property "Isat" "8A"
			(at 330.2 165.1 0)
			(effects
				(font
					(size 1.27 1.27)
					(thickness 0.15)
				)
				(justify left bottom)
				(hide yes)
			)
		)
		(property "IMax" ""
			(at 328.93 160.02 0)
			(effects
				(font
					(size 1.27 1.27)
					(thickness 0.15)
				)
				(justify left bottom)
				(hide yes)
			)
		)
		(property "Imax" "10A"
			(at 330.2 167.64 0)
			(effects
				(font
					(size 1.27 1.27)
					(thickness 0.15)
				)
				(justify left bottom)
				(hide yes)
			)
		)
		(property "Size" "4.2x4.1"
			(at 330.2 170.18 0)
			(effects
				(font
					(size 1.27 1.27)
					(thickness 0.15)
				)
				(justify left bottom)
				(hide yes)
			)
		)
		(property "Author" "Antmicro"
			(at 330.2 172.72 0)
			(effects
				(font
					(size 1.27 1.27)
					(thickness 0.15)
				)
				(justify left bottom)
				(hide yes)
			)
		)
		(property "License" "Apache-2.0"
			(at 330.2 175.26 0)
			(effects
				(font
					(size 1.27 1.27)
					(thickness 0.15)
				)
				(justify left bottom)
				(hide yes)
			)
		)
		(pin "1"
		)
		(pin "2"
		)
		(instances
			(project "thunderbolt-to-10gbe-adapter"
				(path ""
					(reference "L7")
					(unit 1)
				)
			)
		)
	)
	(symbol
		(lib_id "antmicroCapacitors0603:C_22u_16V_0603")
		(at 344.17 76.2 90)
		(unit 1)
		(exclude_from_sim no)
		(in_bom yes)
		(on_board yes)
		(dnp no)
		(property "Reference" "C135"
			(at 346.202 72.39 90)
			(effects
				(font
					(size 1.27 1.27)
					(thickness 0.15)
				)
				(justify right)
			)
		)
		(property "Value" "C_22u_16V_0603"
			(at 354.33 55.88 0)
			(effects
				(font
					(size 1.27 1.27)
					(thickness 0.15)
				)
				(justify left bottom)
				(hide yes)
			)
		)
		(property "Footprint" "antmicro-footprints:C_0603_1608Metric_EIA"
			(at 356.87 55.88 0)
			(effects
				(font
					(size 1.27 1.27)
					(thickness 0.15)
				)
				(justify left bottom)
				(hide yes)
			)
		)
		(property "Datasheet" "https://product.samsungsem.com/mlcc/CL10A226MO7JZN.do"
			(at 359.41 55.88 0)
			(effects
				(font
					(size 1.27 1.27)
					(thickness 0.15)
				)
				(justify left bottom)
				(hide yes)
			)
		)
		(property "Description" "SMD Multilayer Ceramic Capacitor"
			(at 344.17 76.2 0)
			(effects
				(font
					(size 1.27 1.27)
				)
				(hide yes)
			)
		)
		(property "MPN" "CL10A226MO7JZNC"
			(at 361.95 55.88 0)
			(effects
				(font
					(size 1.27 1.27)
					(thickness 0.15)
				)
				(justify left bottom)
				(hide yes)
			)
		)
		(property "Manufacturer" "Samsung Electro-Mechanics"
			(at 364.49 55.88 0)
			(effects
				(font
					(size 1.27 1.27)
					(thickness 0.15)
				)
				(justify left bottom)
				(hide yes)
			)
		)
		(property "License" "Apache-2.0"
			(at 367.03 55.88 0)
			(effects
				(font
					(size 1.27 1.27)
					(thickness 0.15)
				)
				(justify left bottom)
				(hide yes)
			)
		)
		(property "Author" "Antmicro"
			(at 369.57 55.88 0)
			(effects
				(font
					(size 1.27 1.27)
					(thickness 0.15)
				)
				(justify left bottom)
				(hide yes)
			)
		)
		(property "Val" "22u"
			(at 346.202 74.93 90)
			(effects
				(font
					(size 1.27 1.27)
					(thickness 0.15)
				)
				(justify right)
			)
		)
		(property "Voltage" "16V"
			(at 346.71 76.1935 90)
			(effects
				(font
					(size 1.27 1.27)
				)
				(justify right)
				(hide yes)
			)
		)
		(property "Dielectric" ""
			(at 374.65 55.88 0)
			(effects
				(font
					(size 1.27 1.27)
				)
				(justify left bottom)
				(hide yes)
			)
		)
		(pin "2"
		)
		(pin "1"
		)
		(instances
			(project "thunderbolt-to-10gbe-adapter"
				(path ""
					(reference "C135")
					(unit 1)
				)
			)
		)
	)
	(symbol
		(lib_id "antmicroCapacitors0402:C_100n_0402")
		(at 307.34 106.68 270)
		(mirror x)
		(unit 1)
		(exclude_from_sim no)
		(in_bom yes)
		(on_board yes)
		(dnp no)
		(property "Reference" "C126"
			(at 309.118 103.124 90)
			(effects
				(font
					(size 1.27 1.27)
					(thickness 0.15)
				)
				(justify left)
			)
		)
		(property "Value" "C_100n_0402"
			(at 297.18 86.36 0)
			(effects
				(font
					(size 1.27 1.27)
					(thickness 0.15)
				)
				(justify left bottom)
				(hide yes)
			)
		)
		(property "Footprint" "antmicro-footprints:C_0402_1005Metric"
			(at 294.64 86.36 0)
			(effects
				(font
					(size 1.27 1.27)
					(thickness 0.15)
				)
				(justify left bottom)
				(hide yes)
			)
		)
		(property "Datasheet" "https://www.murata.com/products/productdetail?partno=GRM155R61H104KE14%23"
			(at 292.1 86.36 0)
			(effects
				(font
					(size 1.27 1.27)
					(thickness 0.15)
				)
				(justify left bottom)
				(hide yes)
			)
		)
		(property "Description" "SMD Multilayer Ceramic Capacitor, 0.1 µF, 50 V, 0402 [1005 Metric], ± 10%, X5R, GRM Series"
			(at 274.32 86.36 0)
			(effects
				(font
					(size 1.27 1.27)
				)
				(justify left bottom)
				(hide yes)
			)
		)
		(property "MPN" "GRM155R61H104KE14D"
			(at 289.56 86.36 0)
			(effects
				(font
					(size 1.27 1.27)
					(thickness 0.15)
				)
				(justify left bottom)
				(hide yes)
			)
		)
		(property "Manufacturer" "Murata"
			(at 287.02 86.36 0)
			(effects
				(font
					(size 1.27 1.27)
					(thickness 0.15)
				)
				(justify left bottom)
				(hide yes)
			)
		)
		(property "License" "Apache-2.0"
			(at 284.48 86.36 0)
			(effects
				(font
					(size 1.27 1.27)
					(thickness 0.15)
				)
				(justify left bottom)
				(hide yes)
			)
		)
		(property "Author" "Antmicro"
			(at 281.94 86.36 0)
			(effects
				(font
					(size 1.27 1.27)
					(thickness 0.15)
				)
				(justify left bottom)
				(hide yes)
			)
		)
		(property "Val" "100n"
			(at 309.118 105.664 90)
			(effects
				(font
					(size 1.27 1.27)
					(thickness 0.15)
				)
				(justify left)
			)
		)
		(property "Voltage" "50V"
			(at 279.4 86.36 0)
			(effects
				(font
					(size 1.27 1.27)
				)
				(justify left bottom)
				(hide yes)
			)
		)
		(property "Dielectric" "X5R"
			(at 276.86 86.36 0)
			(effects
				(font
					(size 1.27 1.27)
				)
				(justify left bottom)
				(hide yes)
			)
		)
		(pin "1"
		)
		(pin "2"
		)
		(instances
			(project "thunderbolt-to-10gbe-adapter"
				(path ""
					(reference "C126")
					(unit 1)
				)
			)
		)
	)
	(symbol
		(lib_id "antmicroCapacitors0402:C_33p_0402")
		(at 327.66 147.32 270)
		(mirror x)
		(unit 1)
		(exclude_from_sim no)
		(in_bom yes)
		(on_board yes)
		(dnp yes)
		(property "Reference" "C132"
			(at 325.882 143.51 90)
			(effects
				(font
					(size 1.27 1.27)
					(thickness 0.15)
				)
				(justify right)
			)
		)
		(property "Value" "C_33p_0402"
			(at 317.5 127 0)
			(effects
				(font
					(size 1.27 1.27)
					(thickness 0.15)
				)
				(justify left bottom)
				(hide yes)
			)
		)
		(property "Footprint" "antmicro-footprints:C_0402_1005Metric"
			(at 314.96 127 0)
			(effects
				(font
					(size 1.27 1.27)
					(thickness 0.15)
				)
				(justify left bottom)
				(hide yes)
			)
		)
		(property "Datasheet" "https://spicat.kyocera-avx.com/product/mlcc/chartview/04025A330FAT2A/"
			(at 312.42 127 0)
			(effects
				(font
					(size 1.27 1.27)
					(thickness 0.15)
				)
				(justify left bottom)
				(hide yes)
			)
		)
		(property "Description" "SMD Multilayer Ceramic Capacitor, 33 pF, 50 V, 0402 [1005 Metric], ± 5%, C0G / NP0, MC"
			(at 294.64 127 0)
			(effects
				(font
					(size 1.27 1.27)
				)
				(justify left bottom)
				(hide yes)
			)
		)
		(property "MPN" "04025A330FAT2A"
			(at 309.88 127 0)
			(effects
				(font
					(size 1.27 1.27)
					(thickness 0.15)
				)
				(justify left bottom)
				(hide yes)
			)
		)
		(property "Manufacturer" "KYOCERA AVX"
			(at 307.34 127 0)
			(effects
				(font
					(size 1.27 1.27)
					(thickness 0.15)
				)
				(justify left bottom)
				(hide yes)
			)
		)
		(property "License" "Apache-2.0"
			(at 304.8 127 0)
			(effects
				(font
					(size 1.27 1.27)
					(thickness 0.15)
				)
				(justify left bottom)
				(hide yes)
			)
		)
		(property "Author" "Antmicro"
			(at 302.26 127 0)
			(effects
				(font
					(size 1.27 1.27)
					(thickness 0.15)
				)
				(justify left bottom)
				(hide yes)
			)
		)
		(property "Val" "33p"
			(at 325.882 146.05 90)
			(effects
				(font
					(size 1.27 1.27)
					(thickness 0.15)
				)
				(justify right)
			)
		)
		(property "Voltage" ""
			(at 299.72 127 0)
			(effects
				(font
					(size 1.27 1.27)
				)
				(justify left bottom)
				(hide yes)
			)
		)
		(property "Dielectric" ""
			(at 297.18 127 0)
			(effects
				(font
					(size 1.27 1.27)
				)
				(justify left bottom)
				(hide yes)
			)
		)
		(pin "2"
		)
		(pin "1"
		)
		(instances
			(project "thunderbolt-to-10gbe-adapter"
				(path ""
					(reference "C132")
					(unit 1)
				)
			)
		)
	)
	(symbol
		(lib_id "antmicropower:+5V")
		(at 217.17 99.06 0)
		(unit 1)
		(exclude_from_sim no)
		(in_bom yes)
		(on_board yes)
		(dnp no)
		(property "Reference" "#PWR0153"
			(at 232.41 101.6 0)
			(effects
				(font
					(size 1.27 1.27)
					(thickness 0.15)
				)
				(justify left bottom)
				(hide yes)
			)
		)
		(property "Value" "+5V"
			(at 217.17 95.25 0)
			(effects
				(font
					(size 1.27 1.27)
					(thickness 0.15)
				)
			)
		)
		(property "Footprint" ""
			(at 232.41 106.68 0)
			(effects
				(font
					(size 1.27 1.27)
					(thickness 0.15)
				)
				(justify left bottom)
				(hide yes)
			)
		)
		(property "Datasheet" ""
			(at 232.41 109.22 0)
			(effects
				(font
					(size 1.27 1.27)
					(thickness 0.15)
				)
				(justify left bottom)
				(hide yes)
			)
		)
		(property "Description" ""
			(at 232.41 111.76 0)
			(effects
				(font
					(size 1.27 1.27)
				)
				(justify left bottom)
				(hide yes)
			)
		)
		(property "Author" "Antmicro"
			(at 232.41 106.68 0)
			(effects
				(font
					(size 1.27 1.27)
					(thickness 0.15)
				)
				(justify left bottom)
				(hide yes)
			)
		)
		(property "License" "Apache-2.0"
			(at 232.41 109.22 0)
			(effects
				(font
					(size 1.27 1.27)
					(thickness 0.15)
				)
				(justify left bottom)
				(hide yes)
			)
		)
		(pin "1"
		)
		(instances
			(project "thunderbolt-to-10gbe-adapter"
				(path ""
					(reference "#PWR0153")
					(unit 1)
				)
			)
		)
	)
	(symbol
		(lib_id "antmicropower:GND")
		(at 217.17 43.18 0)
		(unit 1)
		(exclude_from_sim no)
		(in_bom yes)
		(on_board yes)
		(dnp no)
		(property "Reference" "#PWR0150"
			(at 226.06 45.72 0)
			(effects
				(font
					(size 1.27 1.27)
					(thickness 0.15)
				)
				(justify left bottom)
				(hide yes)
			)
		)
		(property "Value" "GND"
			(at 217.17 46.99 0)
			(effects
				(font
					(size 1.27 1.27)
					(thickness 0.15)
				)
			)
		)
		(property "Footprint" ""
			(at 226.06 50.8 0)
			(effects
				(font
					(size 1.27 1.27)
					(thickness 0.15)
				)
				(justify left bottom)
				(hide yes)
			)
		)
		(property "Datasheet" ""
			(at 226.06 55.88 0)
			(effects
				(font
					(size 1.27 1.27)
					(thickness 0.15)
				)
				(justify left bottom)
				(hide yes)
			)
		)
		(property "Description" ""
			(at 217.17 43.18 0)
			(effects
				(font
					(size 1.27 1.27)
				)
				(hide yes)
			)
		)
		(property "Author" "Antmicro"
			(at 226.06 50.8 0)
			(effects
				(font
					(size 1.27 1.27)
					(thickness 0.15)
				)
				(justify left bottom)
				(hide yes)
			)
		)
		(property "License" "Apache-2.0"
			(at 226.06 53.34 0)
			(effects
				(font
					(size 1.27 1.27)
					(thickness 0.15)
				)
				(justify left bottom)
				(hide yes)
			)
		)
		(pin "1"
		)
		(instances
			(project "thunderbolt-to-10gbe-adapter"
				(path ""
					(reference "#PWR0150")
					(unit 1)
				)
			)
		)
	)
	(symbol
		(lib_id "antmicropower:VCC")
		(at 400.05 60.96 0)
		(unit 1)
		(exclude_from_sim no)
		(in_bom yes)
		(on_board yes)
		(dnp no)
		(property "Reference" "#PWR0214"
			(at 400.05 64.77 0)
			(effects
				(font
					(size 1.27 1.27)
				)
				(hide yes)
			)
		)
		(property "Value" "VCCD"
			(at 400.05 57.15 0)
			(effects
				(font
					(size 1.27 1.27)
				)
			)
		)
		(property "Footprint" ""
			(at 400.05 60.96 0)
			(effects
				(font
					(size 1.27 1.27)
				)
				(hide yes)
			)
		)
		(property "Datasheet" ""
			(at 400.05 60.96 0)
			(effects
				(font
					(size 1.27 1.27)
				)
				(hide yes)
			)
		)
		(property "Description" ""
			(at 400.05 60.96 0)
			(effects
				(font
					(size 1.27 1.27)
				)
				(hide yes)
			)
		)
		(pin "1"
		)
		(instances
			(project "thunderbolt-to-10gbe-adapter"
				(path ""
					(reference "#PWR0214")
					(unit 1)
				)
			)
		)
	)
	(symbol
		(lib_id "antmicropower:PWR_FLAG")
		(at 391.16 175.26 0)
		(unit 1)
		(exclude_from_sim no)
		(in_bom yes)
		(on_board yes)
		(dnp no)
		(property "Reference" "#FLG023"
			(at 391.16 173.355 0)
			(effects
				(font
					(size 1.27 1.27)
				)
				(hide yes)
			)
		)
		(property "Value" "PWR_FLAG"
			(at 391.16 171.45 0)
			(effects
				(font
					(size 1.27 1.27)
				)
			)
		)
		(property "Footprint" ""
			(at 391.16 175.26 0)
			(effects
				(font
					(size 1.27 1.27)
				)
				(hide yes)
			)
		)
		(property "Datasheet" ""
			(at 391.16 175.26 0)
			(effects
				(font
					(size 1.27 1.27)
				)
				(hide yes)
			)
		)
		(property "Description" ""
			(at 391.16 175.26 0)
			(effects
				(font
					(size 1.27 1.27)
				)
				(hide yes)
			)
		)
		(pin "1"
		)
		(instances
			(project "thunderbolt-to-10gbe-adapter"
				(path ""
					(reference "#FLG023")
					(unit 1)
				)
			)
		)
	)
	(symbol
		(lib_id "antmicropower:GND")
		(at 364.49 157.48 0)
		(unit 1)
		(exclude_from_sim no)
		(in_bom yes)
		(on_board yes)
		(dnp no)
		(property "Reference" "#PWR0201"
			(at 373.38 160.02 0)
			(effects
				(font
					(size 1.27 1.27)
					(thickness 0.15)
				)
				(justify left bottom)
				(hide yes)
			)
		)
		(property "Value" "GND"
			(at 364.49 161.29 0)
			(effects
				(font
					(size 1.27 1.27)
					(thickness 0.15)
				)
			)
		)
		(property "Footprint" ""
			(at 373.38 165.1 0)
			(effects
				(font
					(size 1.27 1.27)
					(thickness 0.15)
				)
				(justify left bottom)
				(hide yes)
			)
		)
		(property "Datasheet" ""
			(at 373.38 170.18 0)
			(effects
				(font
					(size 1.27 1.27)
					(thickness 0.15)
				)
				(justify left bottom)
				(hide yes)
			)
		)
		(property "Description" ""
			(at 364.49 157.48 0)
			(effects
				(font
					(size 1.27 1.27)
				)
				(hide yes)
			)
		)
		(property "Author" "Antmicro"
			(at 373.38 165.1 0)
			(effects
				(font
					(size 1.27 1.27)
					(thickness 0.15)
				)
				(justify left bottom)
				(hide yes)
			)
		)
		(property "License" "Apache-2.0"
			(at 373.38 167.64 0)
			(effects
				(font
					(size 1.27 1.27)
					(thickness 0.15)
				)
				(justify left bottom)
				(hide yes)
			)
		)
		(pin "1"
		)
		(instances
			(project "thunderbolt-to-10gbe-adapter"
				(path ""
					(reference "#PWR0201")
					(unit 1)
				)
			)
		)
	)
	(symbol
		(lib_id "antmicroCapacitors0603:C_22u_16V_0603")
		(at 227.33 76.2 270)
		(mirror x)
		(unit 1)
		(exclude_from_sim no)
		(in_bom yes)
		(on_board yes)
		(dnp no)
		(property "Reference" "C110"
			(at 225.552 72.39 90)
			(effects
				(font
					(size 1.27 1.27)
					(thickness 0.15)
				)
				(justify right)
			)
		)
		(property "Value" "C_22u_16V_0603"
			(at 217.17 55.88 0)
			(effects
				(font
					(size 1.27 1.27)
					(thickness 0.15)
				)
				(justify left bottom)
				(hide yes)
			)
		)
		(property "Footprint" "antmicro-footprints:C_0603_1608Metric_EIA"
			(at 214.63 55.88 0)
			(effects
				(font
					(size 1.27 1.27)
					(thickness 0.15)
				)
				(justify left bottom)
				(hide yes)
			)
		)
		(property "Datasheet" "https://product.samsungsem.com/mlcc/CL10A226MO7JZN.do"
			(at 212.09 55.88 0)
			(effects
				(font
					(size 1.27 1.27)
					(thickness 0.15)
				)
				(justify left bottom)
				(hide yes)
			)
		)
		(property "Description" "SMD Multilayer Ceramic Capacitor"
			(at 227.33 76.2 0)
			(effects
				(font
					(size 1.27 1.27)
				)
				(hide yes)
			)
		)
		(property "MPN" "CL10A226MO7JZNC"
			(at 209.55 55.88 0)
			(effects
				(font
					(size 1.27 1.27)
					(thickness 0.15)
				)
				(justify left bottom)
				(hide yes)
			)
		)
		(property "Manufacturer" "Samsung Electro-Mechanics"
			(at 207.01 55.88 0)
			(effects
				(font
					(size 1.27 1.27)
					(thickness 0.15)
				)
				(justify left bottom)
				(hide yes)
			)
		)
		(property "License" "Apache-2.0"
			(at 204.47 55.88 0)
			(effects
				(font
					(size 1.27 1.27)
					(thickness 0.15)
				)
				(justify left bottom)
				(hide yes)
			)
		)
		(property "Author" "Antmicro"
			(at 201.93 55.88 0)
			(effects
				(font
					(size 1.27 1.27)
					(thickness 0.15)
				)
				(justify left bottom)
				(hide yes)
			)
		)
		(property "Val" "22u"
			(at 225.552 74.93 90)
			(effects
				(font
					(size 1.27 1.27)
					(thickness 0.15)
				)
				(justify right)
			)
		)
		(property "Voltage" "16V"
			(at 224.79 76.1935 90)
			(effects
				(font
					(size 1.27 1.27)
				)
				(justify right)
				(hide yes)
			)
		)
		(property "Dielectric" ""
			(at 196.85 55.88 0)
			(effects
				(font
					(size 1.27 1.27)
				)
				(justify left bottom)
				(hide yes)
			)
		)
		(pin "2"
		)
		(pin "1"
		)
		(instances
			(project "thunderbolt-to-10gbe-adapter"
				(path ""
					(reference "C110")
					(unit 1)
				)
			)
		)
	)
	(symbol
		(lib_id "antmicroTransistorsBipolarSingle:DTC014T_SOT-416")
		(at 195.58 238.76 0)
		(unit 1)
		(exclude_from_sim no)
		(in_bom yes)
		(on_board yes)
		(dnp no)
		(property "Reference" "Q2"
			(at 204.978 240.03 0)
			(effects
				(font
					(size 1.27 1.27)
					(thickness 0.15)
				)
				(justify left)
			)
		)
		(property "Value" "DTC014T_SOT-416"
			(at 220.98 246.38 0)
			(effects
				(font
					(size 1.27 1.27)
					(thickness 0.15)
				)
				(justify left bottom)
				(hide yes)
			)
		)
		(property "Footprint" "antmicro-footprints:SOT-416"
			(at 220.98 248.92 0)
			(effects
				(font
					(size 1.27 1.27)
					(thickness 0.15)
				)
				(justify left bottom)
				(hide yes)
			)
		)
		(property "Datasheet" "https://www.rohm.com/datasheet?p=DTC014TEB&dist=Mouser&media=referral&source=mouser.com&campaign=Mouser"
			(at 220.98 251.46 0)
			(effects
				(font
					(size 1.27 1.27)
					(thickness 0.15)
				)
				(justify left bottom)
				(hide yes)
			)
		)
		(property "Description" "Bipolar (BJT) Single Transistor with built-in base resistor, NPN, 50V, 100mA, 150mW, SOT-416FL, Surface Mount"
			(at 220.98 264.16 0)
			(effects
				(font
					(size 1.27 1.27)
				)
				(justify left bottom)
				(hide yes)
			)
		)
		(property "Manufacturer" "ROHM Semiconductor"
			(at 220.98 254 0)
			(effects
				(font
					(size 1.27 1.27)
					(thickness 0.15)
				)
				(justify left bottom)
				(hide yes)
			)
		)
		(property "MPN" "DTC014TEBTL"
			(at 204.978 242.57 0)
			(effects
				(font
					(size 1.27 1.27)
					(thickness 0.15)
				)
				(justify left)
			)
		)
		(property "Author" "Antmicro"
			(at 220.98 259.08 0)
			(effects
				(font
					(size 1.27 1.27)
					(thickness 0.15)
				)
				(justify left bottom)
				(hide yes)
			)
		)
		(property "License" "Apache-2.0"
			(at 220.98 261.62 0)
			(effects
				(font
					(size 1.27 1.27)
					(thickness 0.15)
				)
				(justify left bottom)
				(hide yes)
			)
		)
		(pin "1"
		)
		(pin "2"
		)
		(pin "3"
		)
		(instances
			(project "thunderbolt-to-10gbe-adapter"
				(path ""
					(reference "Q2")
					(unit 1)
				)
			)
		)
	)
	(symbol
		(lib_id "antmicroResistors0402:R_100k_0402")
		(at 256.54 38.1 270)
		(mirror x)
		(unit 1)
		(exclude_from_sim no)
		(in_bom yes)
		(on_board yes)
		(dnp no)
		(property "Reference" "R87"
			(at 255.27 34.29 90)
			(effects
				(font
					(size 1.27 1.27)
					(thickness 0.15)
				)
				(justify right)
			)
		)
		(property "Value" "R_100k_0402"
			(at 243.84 17.78 0)
			(effects
				(font
					(size 1.27 1.27)
					(thickness 0.15)
				)
				(justify left bottom)
				(hide yes)
			)
		)
		(property "Footprint" "antmicro-footprints:R_0402_1005Metric"
			(at 241.3 17.78 0)
			(effects
				(font
					(size 1.27 1.27)
					(thickness 0.15)
				)
				(justify left bottom)
				(hide yes)
			)
		)
		(property "Datasheet" "https://www.bourns.com/docs/product-datasheets/cr.pdf"
			(at 238.76 17.78 0)
			(effects
				(font
					(size 1.27 1.27)
					(thickness 0.15)
				)
				(justify left bottom)
				(hide yes)
			)
		)
		(property "Description" "SMD Chip Resistor, 100 kohm, ± 1%, 62.5 mW, 0402 [1005 Metric], Thick Film, General Purpose"
			(at 226.06 17.78 0)
			(effects
				(font
					(size 1.27 1.27)
				)
				(justify left bottom)
				(hide yes)
			)
		)
		(property "MPN" "CR0402-FX-1003GLF"
			(at 236.22 17.78 0)
			(effects
				(font
					(size 1.27 1.27)
					(thickness 0.15)
				)
				(justify left bottom)
				(hide yes)
			)
		)
		(property "Manufacturer" "Bourns"
			(at 233.68 17.78 0)
			(effects
				(font
					(size 1.27 1.27)
					(thickness 0.15)
				)
				(justify left bottom)
				(hide yes)
			)
		)
		(property "License" "Apache-2.0"
			(at 231.14 17.78 0)
			(effects
				(font
					(size 1.27 1.27)
					(thickness 0.15)
				)
				(justify left bottom)
				(hide yes)
			)
		)
		(property "Author" "Antmicro"
			(at 228.6 17.78 0)
			(effects
				(font
					(size 1.27 1.27)
					(thickness 0.15)
				)
				(justify left bottom)
				(hide yes)
			)
		)
		(property "Val" "100k"
			(at 255.27 36.83 90)
			(effects
				(font
					(size 1.27 1.27)
					(thickness 0.15)
				)
				(justify right)
			)
		)
		(property "Tolerance" "1%"
			(at 246.38 17.78 0)
			(effects
				(font
					(size 1.27 1.27)
				)
				(justify left bottom)
				(hide yes)
			)
		)
		(pin "1"
		)
		(pin "2"
		)
		(instances
			(project "thunderbolt-to-10gbe-adapter"
				(path ""
					(reference "R87")
					(unit 1)
				)
			)
		)
	)
	(symbol
		(lib_id "antmicroResistors0402:R_100k_0402")
		(at 256.54 76.2 270)
		(mirror x)
		(unit 1)
		(exclude_from_sim no)
		(in_bom yes)
		(on_board yes)
		(dnp no)
		(property "Reference" "R88"
			(at 255.27 72.39 90)
			(effects
				(font
					(size 1.27 1.27)
					(thickness 0.15)
				)
				(justify right)
			)
		)
		(property "Value" "R_100k_0402"
			(at 243.84 55.88 0)
			(effects
				(font
					(size 1.27 1.27)
					(thickness 0.15)
				)
				(justify left bottom)
				(hide yes)
			)
		)
		(property "Footprint" "antmicro-footprints:R_0402_1005Metric"
			(at 241.3 55.88 0)
			(effects
				(font
					(size 1.27 1.27)
					(thickness 0.15)
				)
				(justify left bottom)
				(hide yes)
			)
		)
		(property "Datasheet" "https://www.bourns.com/docs/product-datasheets/cr.pdf"
			(at 238.76 55.88 0)
			(effects
				(font
					(size 1.27 1.27)
					(thickness 0.15)
				)
				(justify left bottom)
				(hide yes)
			)
		)
		(property "Description" "SMD Chip Resistor, 100 kohm, ± 1%, 62.5 mW, 0402 [1005 Metric], Thick Film, General Purpose"
			(at 226.06 55.88 0)
			(effects
				(font
					(size 1.27 1.27)
				)
				(justify left bottom)
				(hide yes)
			)
		)
		(property "MPN" "CR0402-FX-1003GLF"
			(at 236.22 55.88 0)
			(effects
				(font
					(size 1.27 1.27)
					(thickness 0.15)
				)
				(justify left bottom)
				(hide yes)
			)
		)
		(property "Manufacturer" "Bourns"
			(at 233.68 55.88 0)
			(effects
				(font
					(size 1.27 1.27)
					(thickness 0.15)
				)
				(justify left bottom)
				(hide yes)
			)
		)
		(property "License" "Apache-2.0"
			(at 231.14 55.88 0)
			(effects
				(font
					(size 1.27 1.27)
					(thickness 0.15)
				)
				(justify left bottom)
				(hide yes)
			)
		)
		(property "Author" "Antmicro"
			(at 228.6 55.88 0)
			(effects
				(font
					(size 1.27 1.27)
					(thickness 0.15)
				)
				(justify left bottom)
				(hide yes)
			)
		)
		(property "Val" "100k"
			(at 255.27 74.93 90)
			(effects
				(font
					(size 1.27 1.27)
					(thickness 0.15)
				)
				(justify right)
			)
		)
		(property "Tolerance" "1%"
			(at 246.38 55.88 0)
			(effects
				(font
					(size 1.27 1.27)
				)
				(justify left bottom)
				(hide yes)
			)
		)
		(pin "1"
		)
		(pin "2"
		)
		(instances
			(project "thunderbolt-to-10gbe-adapter"
				(path ""
					(reference "R88")
					(unit 1)
				)
			)
		)
	)
	(symbol
		(lib_id "antmicroResistors0402:R_330R_0402")
		(at 304.8 222.25 90)
		(unit 1)
		(exclude_from_sim no)
		(in_bom yes)
		(on_board yes)
		(dnp no)
		(property "Reference" "R97"
			(at 306.07 218.44 90)
			(effects
				(font
					(size 1.27 1.27)
					(thickness 0.15)
				)
				(justify right)
			)
		)
		(property "Value" "R_330R_0402"
			(at 317.5 201.93 0)
			(effects
				(font
					(size 1.27 1.27)
					(thickness 0.15)
				)
				(justify left bottom)
				(hide yes)
			)
		)
		(property "Footprint" "antmicro-footprints:R_0402_1005Metric"
			(at 320.04 201.93 0)
			(effects
				(font
					(size 1.27 1.27)
					(thickness 0.15)
				)
				(justify left bottom)
				(hide yes)
			)
		)
		(property "Datasheet" "https://www.bourns.com/docs/product-datasheets/cr.pdf"
			(at 322.58 201.93 0)
			(effects
				(font
					(size 1.27 1.27)
					(thickness 0.15)
				)
				(justify left bottom)
				(hide yes)
			)
		)
		(property "Description" "SMD Chip Resistor, 330 ohm, ± 1%, 62.5 mW, 0402 [1005 Metric], Thick Film, General Purpose"
			(at 335.28 201.93 0)
			(effects
				(font
					(size 1.27 1.27)
				)
				(justify left bottom)
				(hide yes)
			)
		)
		(property "MPN" "CR0402-FX-3300GLF"
			(at 325.12 201.93 0)
			(effects
				(font
					(size 1.27 1.27)
					(thickness 0.15)
				)
				(justify left bottom)
				(hide yes)
			)
		)
		(property "Manufacturer" "Bourns"
			(at 327.66 201.93 0)
			(effects
				(font
					(size 1.27 1.27)
					(thickness 0.15)
				)
				(justify left bottom)
				(hide yes)
			)
		)
		(property "License" "Apache-2.0"
			(at 330.2 201.93 0)
			(effects
				(font
					(size 1.27 1.27)
					(thickness 0.15)
				)
				(justify left bottom)
				(hide yes)
			)
		)
		(property "Author" "Antmicro"
			(at 332.74 201.93 0)
			(effects
				(font
					(size 1.27 1.27)
					(thickness 0.15)
				)
				(justify left bottom)
				(hide yes)
			)
		)
		(property "Val" "330R"
			(at 306.07 220.98 90)
			(effects
				(font
					(size 1.27 1.27)
					(thickness 0.15)
				)
				(justify right)
			)
		)
		(property "Tolerance" "1%"
			(at 314.96 201.93 0)
			(effects
				(font
					(size 1.27 1.27)
				)
				(justify left bottom)
				(hide yes)
			)
		)
		(pin "2"
		)
		(pin "1"
		)
		(instances
			(project "thunderbolt-to-10gbe-adapter"
				(path ""
					(reference "R97")
					(unit 1)
				)
			)
		)
	)
	(symbol
		(lib_id "antmicroCapacitors0402:C_100n_0402")
		(at 374.65 38.1 90)
		(unit 1)
		(exclude_from_sim no)
		(in_bom yes)
		(on_board yes)
		(dnp no)
		(property "Reference" "C149"
			(at 376.428 34.29 90)
			(effects
				(font
					(size 1.27 1.27)
					(thickness 0.15)
				)
				(justify right)
			)
		)
		(property "Value" "C_100n_0402"
			(at 384.81 17.78 0)
			(effects
				(font
					(size 1.27 1.27)
					(thickness 0.15)
				)
				(justify left bottom)
				(hide yes)
			)
		)
		(property "Footprint" "antmicro-footprints:C_0402_1005Metric"
			(at 387.35 17.78 0)
			(effects
				(font
					(size 1.27 1.27)
					(thickness 0.15)
				)
				(justify left bottom)
				(hide yes)
			)
		)
		(property "Datasheet" "https://www.murata.com/products/productdetail?partno=GRM155R61H104KE14%23"
			(at 389.89 17.78 0)
			(effects
				(font
					(size 1.27 1.27)
					(thickness 0.15)
				)
				(justify left bottom)
				(hide yes)
			)
		)
		(property "Description" "SMD Multilayer Ceramic Capacitor, 0.1 µF, 50 V, 0402 [1005 Metric], ± 10%, X5R, GRM Series"
			(at 407.67 17.78 0)
			(effects
				(font
					(size 1.27 1.27)
				)
				(justify left bottom)
				(hide yes)
			)
		)
		(property "MPN" "GRM155R61H104KE14D"
			(at 392.43 17.78 0)
			(effects
				(font
					(size 1.27 1.27)
					(thickness 0.15)
				)
				(justify left bottom)
				(hide yes)
			)
		)
		(property "Manufacturer" "Murata"
			(at 394.97 17.78 0)
			(effects
				(font
					(size 1.27 1.27)
					(thickness 0.15)
				)
				(justify left bottom)
				(hide yes)
			)
		)
		(property "License" "Apache-2.0"
			(at 397.51 17.78 0)
			(effects
				(font
					(size 1.27 1.27)
					(thickness 0.15)
				)
				(justify left bottom)
				(hide yes)
			)
		)
		(property "Author" "Antmicro"
			(at 400.05 17.78 0)
			(effects
				(font
					(size 1.27 1.27)
					(thickness 0.15)
				)
				(justify left bottom)
				(hide yes)
			)
		)
		(property "Val" "100n"
			(at 376.428 36.83 90)
			(effects
				(font
					(size 1.27 1.27)
					(thickness 0.15)
				)
				(justify right)
			)
		)
		(property "Voltage" "50V"
			(at 402.59 17.78 0)
			(effects
				(font
					(size 1.27 1.27)
				)
				(justify left bottom)
				(hide yes)
			)
		)
		(property "Dielectric" "X5R"
			(at 405.13 17.78 0)
			(effects
				(font
					(size 1.27 1.27)
				)
				(justify left bottom)
				(hide yes)
			)
		)
		(pin "1"
		)
		(pin "2"
		)
		(instances
			(project "thunderbolt-to-10gbe-adapter"
				(path ""
					(reference "C149")
					(unit 1)
				)
			)
		)
	)
	(symbol
		(lib_id "antmicroCapacitors0603:C_22u_16V_0603")
		(at 344.17 152.4 90)
		(unit 1)
		(exclude_from_sim no)
		(in_bom yes)
		(on_board yes)
		(dnp no)
		(property "Reference" "C137"
			(at 346.202 148.59 90)
			(effects
				(font
					(size 1.27 1.27)
					(thickness 0.15)
				)
				(justify right)
			)
		)
		(property "Value" "C_22u_16V_0603"
			(at 354.33 132.08 0)
			(effects
				(font
					(size 1.27 1.27)
					(thickness 0.15)
				)
				(justify left bottom)
				(hide yes)
			)
		)
		(property "Footprint" "antmicro-footprints:C_0603_1608Metric_EIA"
			(at 356.87 132.08 0)
			(effects
				(font
					(size 1.27 1.27)
					(thickness 0.15)
				)
				(justify left bottom)
				(hide yes)
			)
		)
		(property "Datasheet" "https://product.samsungsem.com/mlcc/CL10A226MO7JZN.do"
			(at 359.41 132.08 0)
			(effects
				(font
					(size 1.27 1.27)
					(thickness 0.15)
				)
				(justify left bottom)
				(hide yes)
			)
		)
		(property "Description" "SMD Multilayer Ceramic Capacitor"
			(at 344.17 152.4 0)
			(effects
				(font
					(size 1.27 1.27)
				)
				(hide yes)
			)
		)
		(property "MPN" "CL10A226MO7JZNC"
			(at 361.95 132.08 0)
			(effects
				(font
					(size 1.27 1.27)
					(thickness 0.15)
				)
				(justify left bottom)
				(hide yes)
			)
		)
		(property "Manufacturer" "Samsung Electro-Mechanics"
			(at 364.49 132.08 0)
			(effects
				(font
					(size 1.27 1.27)
					(thickness 0.15)
				)
				(justify left bottom)
				(hide yes)
			)
		)
		(property "License" "Apache-2.0"
			(at 367.03 132.08 0)
			(effects
				(font
					(size 1.27 1.27)
					(thickness 0.15)
				)
				(justify left bottom)
				(hide yes)
			)
		)
		(property "Author" "Antmicro"
			(at 369.57 132.08 0)
			(effects
				(font
					(size 1.27 1.27)
					(thickness 0.15)
				)
				(justify left bottom)
				(hide yes)
			)
		)
		(property "Val" "22u"
			(at 346.202 151.13 90)
			(effects
				(font
					(size 1.27 1.27)
					(thickness 0.15)
				)
				(justify right)
			)
		)
		(property "Voltage" "16V"
			(at 346.71 152.3935 90)
			(effects
				(font
					(size 1.27 1.27)
				)
				(justify right)
				(hide yes)
			)
		)
		(property "Dielectric" ""
			(at 374.65 132.08 0)
			(effects
				(font
					(size 1.27 1.27)
				)
				(justify left bottom)
				(hide yes)
			)
		)
		(pin "2"
		)
		(pin "1"
		)
		(instances
			(project "thunderbolt-to-10gbe-adapter"
				(path ""
					(reference "C137")
					(unit 1)
				)
			)
		)
	)
	(symbol
		(lib_id "antmicropower:GND")
		(at 344.17 43.18 0)
		(unit 1)
		(exclude_from_sim no)
		(in_bom yes)
		(on_board yes)
		(dnp no)
		(property "Reference" "#PWR0188"
			(at 353.06 45.72 0)
			(effects
				(font
					(size 1.27 1.27)
					(thickness 0.15)
				)
				(justify left bottom)
				(hide yes)
			)
		)
		(property "Value" "GND"
			(at 344.17 46.99 0)
			(effects
				(font
					(size 1.27 1.27)
					(thickness 0.15)
				)
			)
		)
		(property "Footprint" ""
			(at 353.06 50.8 0)
			(effects
				(font
					(size 1.27 1.27)
					(thickness 0.15)
				)
				(justify left bottom)
				(hide yes)
			)
		)
		(property "Datasheet" ""
			(at 353.06 55.88 0)
			(effects
				(font
					(size 1.27 1.27)
					(thickness 0.15)
				)
				(justify left bottom)
				(hide yes)
			)
		)
		(property "Description" ""
			(at 344.17 43.18 0)
			(effects
				(font
					(size 1.27 1.27)
				)
				(hide yes)
			)
		)
		(property "Author" "Antmicro"
			(at 353.06 50.8 0)
			(effects
				(font
					(size 1.27 1.27)
					(thickness 0.15)
				)
				(justify left bottom)
				(hide yes)
			)
		)
		(property "License" "Apache-2.0"
			(at 353.06 53.34 0)
			(effects
				(font
					(size 1.27 1.27)
					(thickness 0.15)
				)
				(justify left bottom)
				(hide yes)
			)
		)
		(pin "1"
		)
		(instances
			(project "thunderbolt-to-10gbe-adapter"
				(path ""
					(reference "#PWR0188")
					(unit 1)
				)
			)
		)
	)
	(symbol
		(lib_id "antmicroResistors0603:R_0R_22.4A_0603")
		(at 379.73 101.6 0)
		(unit 1)
		(exclude_from_sim no)
		(in_bom yes)
		(on_board yes)
		(dnp no)
		(property "Reference" "R110"
			(at 379.73 100.33 0)
			(effects
				(font
					(size 1.27 1.27)
					(thickness 0.15)
				)
				(justify right)
			)
		)
		(property "Value" "R_0R_22.4A_0603"
			(at 394.97 106.68 0)
			(effects
				(font
					(size 1.27 1.27)
					(thickness 0.15)
				)
				(justify left bottom)
				(hide yes)
			)
		)
		(property "Footprint" "antmicro-footprints:R_0603_1608Metric"
			(at 394.97 111.76 0)
			(effects
				(font
					(size 1.27 1.27)
					(thickness 0.15)
				)
				(justify left bottom)
				(hide yes)
			)
		)
		(property "Datasheet" "https://fscdn.rohm.com/en/products/databook/datasheet/passive/resistor/chip_resistor/pmr-jpw-e.pdf"
			(at 394.97 114.3 0)
			(effects
				(font
					(size 1.27 1.27)
					(thickness 0.15)
				)
				(justify left bottom)
				(hide yes)
			)
		)
		(property "Description" "SMD Chip Resistor"
			(at 394.97 129.54 0)
			(effects
				(font
					(size 1.27 1.27)
				)
				(justify left bottom)
				(hide yes)
			)
		)
		(property "MPN" "PMR03EZPJ000"
			(at 394.97 116.84 0)
			(effects
				(font
					(size 1.27 1.27)
					(thickness 0.15)
				)
				(justify left bottom)
				(hide yes)
			)
		)
		(property "Manufacturer" "ROHM Semiconductor"
			(at 394.97 119.38 0)
			(effects
				(font
					(size 1.27 1.27)
					(thickness 0.15)
				)
				(justify left bottom)
				(hide yes)
			)
		)
		(property "Val" "0R"
			(at 384.81 100.33 0)
			(effects
				(font
					(size 1.27 1.27)
					(thickness 0.15)
				)
				(justify left)
			)
		)
		(property "Max. Curr." "22.4A"
			(at 382.27 104.14 0)
			(effects
				(font
					(size 1.27 1.27)
					(thickness 0.15)
				)
			)
		)
		(property "Author" "Antmicro"
			(at 394.97 124.46 0)
			(effects
				(font
					(size 1.27 1.27)
					(thickness 0.15)
				)
				(justify left bottom)
				(hide yes)
			)
		)
		(property "License" "Apache-2.0"
			(at 394.97 127 0)
			(effects
				(font
					(size 1.27 1.27)
					(thickness 0.15)
				)
				(justify left bottom)
				(hide yes)
			)
		)
		(property "Tolerance" "template_tolerance"
			(at 400.05 111.76 0)
			(effects
				(font
					(size 1.27 1.27)
				)
				(justify left bottom)
				(hide yes)
			)
		)
		(pin "1"
		)
		(pin "2"
		)
		(instances
			(project "thunderbolt-to-10gbe-adapter"
				(path ""
					(reference "R110")
					(unit 1)
				)
			)
		)
	)
	(symbol
		(lib_id "antmicropower:+3V3")
		(at 387.35 228.6 90)
		(unit 1)
		(exclude_from_sim no)
		(in_bom yes)
		(on_board yes)
		(dnp no)
		(fields_autoplaced yes)
		(property "Reference" "#PWR0208"
			(at 387.35 213.36 0)
			(effects
				(font
					(size 1.27 1.27)
					(thickness 0.15)
				)
				(justify left bottom)
				(hide yes)
			)
		)
		(property "Value" "+3V3"
			(at 383.54 228.6 90)
			(effects
				(font
					(size 1.27 1.27)
					(thickness 0.15)
				)
				(justify left)
			)
		)
		(property "Footprint" ""
			(at 394.97 213.36 0)
			(effects
				(font
					(size 1.27 1.27)
					(thickness 0.15)
				)
				(justify left bottom)
				(hide yes)
			)
		)
		(property "Datasheet" ""
			(at 397.51 213.36 0)
			(effects
				(font
					(size 1.27 1.27)
					(thickness 0.15)
				)
				(justify left bottom)
				(hide yes)
			)
		)
		(property "Description" ""
			(at 387.35 228.6 0)
			(effects
				(font
					(size 1.27 1.27)
				)
				(hide yes)
			)
		)
		(property "Author" "Antmicro"
			(at 389.89 213.36 0)
			(effects
				(font
					(size 1.27 1.27)
					(thickness 0.15)
				)
				(justify left bottom)
				(hide yes)
			)
		)
		(property "License" "Apache-2.0"
			(at 392.43 213.36 0)
			(effects
				(font
					(size 1.27 1.27)
					(thickness 0.15)
				)
				(justify left bottom)
				(hide yes)
			)
		)
		(pin "1"
		)
		(instances
			(project "thunderbolt-to-10gbe-adapter"
				(path ""
					(reference "#PWR0208")
					(unit 1)
				)
			)
		)
	)
	(symbol
		(lib_id "antmicroCapacitors0603:C_22u_16V_0603")
		(at 354.33 152.4 90)
		(unit 1)
		(exclude_from_sim no)
		(in_bom yes)
		(on_board yes)
		(dnp no)
		(property "Reference" "C142"
			(at 356.108 148.59 90)
			(effects
				(font
					(size 1.27 1.27)
					(thickness 0.15)
				)
				(justify right)
			)
		)
		(property "Value" "C_22u_16V_0603"
			(at 364.49 132.08 0)
			(effects
				(font
					(size 1.27 1.27)
					(thickness 0.15)
				)
				(justify left bottom)
				(hide yes)
			)
		)
		(property "Footprint" "antmicro-footprints:C_0603_1608Metric_EIA"
			(at 367.03 132.08 0)
			(effects
				(font
					(size 1.27 1.27)
					(thickness 0.15)
				)
				(justify left bottom)
				(hide yes)
			)
		)
		(property "Datasheet" "https://product.samsungsem.com/mlcc/CL10A226MO7JZN.do"
			(at 369.57 132.08 0)
			(effects
				(font
					(size 1.27 1.27)
					(thickness 0.15)
				)
				(justify left bottom)
				(hide yes)
			)
		)
		(property "Description" "SMD Multilayer Ceramic Capacitor"
			(at 354.33 152.4 0)
			(effects
				(font
					(size 1.27 1.27)
				)
				(hide yes)
			)
		)
		(property "MPN" "CL10A226MO7JZNC"
			(at 372.11 132.08 0)
			(effects
				(font
					(size 1.27 1.27)
					(thickness 0.15)
				)
				(justify left bottom)
				(hide yes)
			)
		)
		(property "Manufacturer" "Samsung Electro-Mechanics"
			(at 374.65 132.08 0)
			(effects
				(font
					(size 1.27 1.27)
					(thickness 0.15)
				)
				(justify left bottom)
				(hide yes)
			)
		)
		(property "License" "Apache-2.0"
			(at 377.19 132.08 0)
			(effects
				(font
					(size 1.27 1.27)
					(thickness 0.15)
				)
				(justify left bottom)
				(hide yes)
			)
		)
		(property "Author" "Antmicro"
			(at 379.73 132.08 0)
			(effects
				(font
					(size 1.27 1.27)
					(thickness 0.15)
				)
				(justify left bottom)
				(hide yes)
			)
		)
		(property "Val" "22u"
			(at 356.108 151.13 90)
			(effects
				(font
					(size 1.27 1.27)
					(thickness 0.15)
				)
				(justify right)
			)
		)
		(property "Voltage" "16V"
			(at 356.87 152.3935 90)
			(effects
				(font
					(size 1.27 1.27)
				)
				(justify right)
				(hide yes)
			)
		)
		(property "Dielectric" ""
			(at 384.81 132.08 0)
			(effects
				(font
					(size 1.27 1.27)
				)
				(justify left bottom)
				(hide yes)
			)
		)
		(pin "2"
		)
		(pin "1"
		)
		(instances
			(project "thunderbolt-to-10gbe-adapter"
				(path ""
					(reference "C142")
					(unit 1)
				)
			)
		)
	)
	(symbol
		(lib_id "antmicroFixedInductors:L_2u2_5.8A_WE-PMFI-35329222")
		(at 314.96 25.4 0)
		(unit 1)
		(exclude_from_sim no)
		(in_bom yes)
		(on_board yes)
		(dnp no)
		(fields_autoplaced yes)
		(property "Reference" "L4"
			(at 317.5 20.32 0)
			(effects
				(font
					(size 1.27 1.27)
					(thickness 0.15)
				)
			)
		)
		(property "Value" "L_2u2_5.8A_WE-PMFI-35329222"
			(at 328.93 27.94 0)
			(effects
				(font
					(size 1.27 1.27)
					(thickness 0.15)
				)
				(justify left bottom)
				(hide yes)
			)
		)
		(property "Footprint" "antmicro-footprints:L_WE-PMFI-353220"
			(at 328.93 33.02 0)
			(effects
				(font
					(size 1.27 1.27)
					(thickness 0.15)
				)
				(justify left bottom)
				(hide yes)
			)
		)
		(property "Datasheet" "https://www.we-online.com/components/products/datasheet/74479335329222.pdf"
			(at 328.93 35.56 0)
			(effects
				(font
					(size 1.27 1.27)
					(thickness 0.15)
				)
				(justify left bottom)
				(hide yes)
			)
		)
		(property "Description" "Power Inductors - SMD WE-PMFI 2.2 uH 5.8 A 40 mOhms AEC-Q200"
			(at 328.93 55.88 0)
			(effects
				(font
					(size 1.27 1.27)
				)
				(justify left bottom)
				(hide yes)
			)
		)
		(property "Val" "2u2/5.8A"
			(at 317.5 22.86 0)
			(effects
				(font
					(size 1.27 1.27)
					(thickness 0.15)
				)
			)
		)
		(property "Manufacturer" "Würth Elektronik"
			(at 328.93 38.1 0)
			(effects
				(font
					(size 1.27 1.27)
					(thickness 0.15)
				)
				(justify left bottom)
				(hide yes)
			)
		)
		(property "MPN" "74479335329222"
			(at 328.93 40.64 0)
			(effects
				(font
					(size 1.27 1.27)
					(thickness 0.15)
				)
				(justify left bottom)
				(hide yes)
			)
		)
		(property "ISat" "7.8A"
			(at 328.93 43.18 0)
			(effects
				(font
					(size 1.27 1.27)
				)
				(justify left bottom)
				(hide yes)
			)
		)
		(property "IMax" "5.8A"
			(at 328.93 45.72 0)
			(effects
				(font
					(size 1.27 1.27)
					(thickness 0.15)
				)
				(justify left bottom)
				(hide yes)
			)
		)
		(property "Size" "3.5x3.2x2.0"
			(at 328.93 48.26 0)
			(effects
				(font
					(size 1.27 1.27)
					(thickness 0.15)
				)
				(justify left bottom)
				(hide yes)
			)
		)
		(property "Author" "Antmicro"
			(at 328.93 50.8 0)
			(effects
				(font
					(size 1.27 1.27)
					(thickness 0.15)
				)
				(justify left bottom)
				(hide yes)
			)
		)
		(property "License" "Apache-2.0"
			(at 328.93 53.34 0)
			(effects
				(font
					(size 1.27 1.27)
					(thickness 0.15)
				)
				(justify left bottom)
				(hide yes)
			)
		)
		(pin "1"
		)
		(pin "2"
		)
		(instances
			(project "thunderbolt-to-10gbe-adapter"
				(path ""
					(reference "L4")
					(unit 1)
				)
			)
		)
	)
	(symbol
		(lib_id "antmicroCapacitors0603:C_22u_16V_0603")
		(at 217.17 152.4 270)
		(mirror x)
		(unit 1)
		(exclude_from_sim no)
		(in_bom yes)
		(on_board yes)
		(dnp no)
		(property "Reference" "C107"
			(at 215.138 148.59 90)
			(effects
				(font
					(size 1.27 1.27)
					(thickness 0.15)
				)
				(justify right)
			)
		)
		(property "Value" "C_22u_16V_0603"
			(at 207.01 132.08 0)
			(effects
				(font
					(size 1.27 1.27)
					(thickness 0.15)
				)
				(justify left bottom)
				(hide yes)
			)
		)
		(property "Footprint" "antmicro-footprints:C_0603_1608Metric_EIA"
			(at 204.47 132.08 0)
			(effects
				(font
					(size 1.27 1.27)
					(thickness 0.15)
				)
				(justify left bottom)
				(hide yes)
			)
		)
		(property "Datasheet" "https://product.samsungsem.com/mlcc/CL10A226MO7JZN.do"
			(at 201.93 132.08 0)
			(effects
				(font
					(size 1.27 1.27)
					(thickness 0.15)
				)
				(justify left bottom)
				(hide yes)
			)
		)
		(property "Description" "SMD Multilayer Ceramic Capacitor"
			(at 217.17 152.4 0)
			(effects
				(font
					(size 1.27 1.27)
				)
				(hide yes)
			)
		)
		(property "MPN" "CL10A226MO7JZNC"
			(at 199.39 132.08 0)
			(effects
				(font
					(size 1.27 1.27)
					(thickness 0.15)
				)
				(justify left bottom)
				(hide yes)
			)
		)
		(property "Manufacturer" "Samsung Electro-Mechanics"
			(at 196.85 132.08 0)
			(effects
				(font
					(size 1.27 1.27)
					(thickness 0.15)
				)
				(justify left bottom)
				(hide yes)
			)
		)
		(property "License" "Apache-2.0"
			(at 194.31 132.08 0)
			(effects
				(font
					(size 1.27 1.27)
					(thickness 0.15)
				)
				(justify left bottom)
				(hide yes)
			)
		)
		(property "Author" "Antmicro"
			(at 191.77 132.08 0)
			(effects
				(font
					(size 1.27 1.27)
					(thickness 0.15)
				)
				(justify left bottom)
				(hide yes)
			)
		)
		(property "Val" "22u"
			(at 215.138 151.13 90)
			(effects
				(font
					(size 1.27 1.27)
					(thickness 0.15)
				)
				(justify right)
			)
		)
		(property "Voltage" "16V"
			(at 214.63 152.3935 90)
			(effects
				(font
					(size 1.27 1.27)
				)
				(justify right)
				(hide yes)
			)
		)
		(property "Dielectric" ""
			(at 186.69 132.08 0)
			(effects
				(font
					(size 1.27 1.27)
				)
				(justify left bottom)
				(hide yes)
			)
		)
		(pin "2"
		)
		(pin "1"
		)
		(instances
			(project "thunderbolt-to-10gbe-adapter"
				(path ""
					(reference "C107")
					(unit 1)
				)
			)
		)
	)
	(symbol
		(lib_id "antmicropower:GND")
		(at 217.17 195.58 0)
		(unit 1)
		(exclude_from_sim no)
		(in_bom yes)
		(on_board yes)
		(dnp no)
		(property "Reference" "#PWR0158"
			(at 226.06 198.12 0)
			(effects
				(font
					(size 1.27 1.27)
					(thickness 0.15)
				)
				(justify left bottom)
				(hide yes)
			)
		)
		(property "Value" "GND"
			(at 217.17 199.39 0)
			(effects
				(font
					(size 1.27 1.27)
					(thickness 0.15)
				)
			)
		)
		(property "Footprint" ""
			(at 226.06 203.2 0)
			(effects
				(font
					(size 1.27 1.27)
					(thickness 0.15)
				)
				(justify left bottom)
				(hide yes)
			)
		)
		(property "Datasheet" ""
			(at 226.06 208.28 0)
			(effects
				(font
					(size 1.27 1.27)
					(thickness 0.15)
				)
				(justify left bottom)
				(hide yes)
			)
		)
		(property "Description" ""
			(at 217.17 195.58 0)
			(effects
				(font
					(size 1.27 1.27)
				)
				(hide yes)
			)
		)
		(property "Author" "Antmicro"
			(at 226.06 203.2 0)
			(effects
				(font
					(size 1.27 1.27)
					(thickness 0.15)
				)
				(justify left bottom)
				(hide yes)
			)
		)
		(property "License" "Apache-2.0"
			(at 226.06 205.74 0)
			(effects
				(font
					(size 1.27 1.27)
					(thickness 0.15)
				)
				(justify left bottom)
				(hide yes)
			)
		)
		(pin "1"
		)
		(instances
			(project "thunderbolt-to-10gbe-adapter"
				(path ""
					(reference "#PWR0158")
					(unit 1)
				)
			)
		)
	)
	(symbol
		(lib_id "antmicroResistors0402:R_330R_0402")
		(at 254 231.14 90)
		(unit 1)
		(exclude_from_sim no)
		(in_bom yes)
		(on_board yes)
		(dnp no)
		(property "Reference" "R86"
			(at 255.27 227.33 90)
			(effects
				(font
					(size 1.27 1.27)
					(thickness 0.15)
				)
				(justify right)
			)
		)
		(property "Value" "R_330R_0402"
			(at 266.7 210.82 0)
			(effects
				(font
					(size 1.27 1.27)
					(thickness 0.15)
				)
				(justify left bottom)
				(hide yes)
			)
		)
		(property "Footprint" "antmicro-footprints:R_0402_1005Metric"
			(at 269.24 210.82 0)
			(effects
				(font
					(size 1.27 1.27)
					(thickness 0.15)
				)
				(justify left bottom)
				(hide yes)
			)
		)
		(property "Datasheet" "https://www.bourns.com/docs/product-datasheets/cr.pdf"
			(at 271.78 210.82 0)
			(effects
				(font
					(size 1.27 1.27)
					(thickness 0.15)
				)
				(justify left bottom)
				(hide yes)
			)
		)
		(property "Description" "SMD Chip Resistor, 330 ohm, ± 1%, 62.5 mW, 0402 [1005 Metric], Thick Film, General Purpose"
			(at 284.48 210.82 0)
			(effects
				(font
					(size 1.27 1.27)
				)
				(justify left bottom)
				(hide yes)
			)
		)
		(property "MPN" "CR0402-FX-3300GLF"
			(at 274.32 210.82 0)
			(effects
				(font
					(size 1.27 1.27)
					(thickness 0.15)
				)
				(justify left bottom)
				(hide yes)
			)
		)
		(property "Manufacturer" "Bourns"
			(at 276.86 210.82 0)
			(effects
				(font
					(size 1.27 1.27)
					(thickness 0.15)
				)
				(justify left bottom)
				(hide yes)
			)
		)
		(property "License" "Apache-2.0"
			(at 279.4 210.82 0)
			(effects
				(font
					(size 1.27 1.27)
					(thickness 0.15)
				)
				(justify left bottom)
				(hide yes)
			)
		)
		(property "Author" "Antmicro"
			(at 281.94 210.82 0)
			(effects
				(font
					(size 1.27 1.27)
					(thickness 0.15)
				)
				(justify left bottom)
				(hide yes)
			)
		)
		(property "Val" "330R"
			(at 255.27 229.87 90)
			(effects
				(font
					(size 1.27 1.27)
					(thickness 0.15)
				)
				(justify right)
			)
		)
		(property "Tolerance" "1%"
			(at 264.16 210.82 0)
			(effects
				(font
					(size 1.27 1.27)
				)
				(justify left bottom)
				(hide yes)
			)
		)
		(pin "2"
		)
		(pin "1"
		)
		(instances
			(project "thunderbolt-to-10gbe-adapter"
				(path ""
					(reference "R86")
					(unit 1)
				)
			)
		)
	)
	(symbol
		(lib_id "antmicroResistors0402:R_30k_0402")
		(at 332.74 118.11 90)
		(unit 1)
		(exclude_from_sim no)
		(in_bom yes)
		(on_board yes)
		(dnp no)
		(property "Reference" "R103"
			(at 334.01 114.3 90)
			(effects
				(font
					(size 1.27 1.27)
					(thickness 0.15)
				)
				(justify right)
			)
		)
		(property "Value" "R_30k_0402"
			(at 345.44 97.79 0)
			(effects
				(font
					(size 1.27 1.27)
					(thickness 0.15)
				)
				(justify left bottom)
				(hide yes)
			)
		)
		(property "Footprint" "antmicro-footprints:R_0402_1005Metric"
			(at 347.98 97.79 0)
			(effects
				(font
					(size 1.27 1.27)
					(thickness 0.15)
				)
				(justify left bottom)
				(hide yes)
			)
		)
		(property "Datasheet" "https://www.bourns.com/docs/product-datasheets/cr.pdf"
			(at 350.52 97.79 0)
			(effects
				(font
					(size 1.27 1.27)
					(thickness 0.15)
				)
				(justify left bottom)
				(hide yes)
			)
		)
		(property "Description" "SMD Chip Resistor, 30 kohm, ± 1%, 63 mW, 0402 [1005 Metric], Thick Film, General Purpose"
			(at 363.22 97.79 0)
			(effects
				(font
					(size 1.27 1.27)
				)
				(justify left bottom)
				(hide yes)
			)
		)
		(property "MPN" "CR0402-FX-3002GLF"
			(at 353.06 97.79 0)
			(effects
				(font
					(size 1.27 1.27)
					(thickness 0.15)
				)
				(justify left bottom)
				(hide yes)
			)
		)
		(property "Manufacturer" "Bourns"
			(at 355.6 97.79 0)
			(effects
				(font
					(size 1.27 1.27)
					(thickness 0.15)
				)
				(justify left bottom)
				(hide yes)
			)
		)
		(property "License" "Apache-2.0"
			(at 358.14 97.79 0)
			(effects
				(font
					(size 1.27 1.27)
					(thickness 0.15)
				)
				(justify left bottom)
				(hide yes)
			)
		)
		(property "Author" "Antmicro"
			(at 360.68 97.79 0)
			(effects
				(font
					(size 1.27 1.27)
					(thickness 0.15)
				)
				(justify left bottom)
				(hide yes)
			)
		)
		(property "Val" "30k"
			(at 334.01 116.84 90)
			(effects
				(font
					(size 1.27 1.27)
					(thickness 0.15)
				)
				(justify right)
			)
		)
		(property "Tolerance" "1%"
			(at 342.9 97.79 0)
			(effects
				(font
					(size 1.27 1.27)
				)
				(justify left bottom)
				(hide yes)
			)
		)
		(pin "2"
		)
		(pin "1"
		)
		(instances
			(project "thunderbolt-to-10gbe-adapter"
				(path ""
					(reference "R103")
					(unit 1)
				)
			)
		)
	)
	(symbol
		(lib_id "antmicroDCDCConverters:TPS566231P")
		(at 276.86 63.5 0)
		(unit 1)
		(exclude_from_sim no)
		(in_bom yes)
		(on_board yes)
		(dnp no)
		(fields_autoplaced yes)
		(property "Reference" "U10"
			(at 285.75 57.15 0)
			(effects
				(font
					(size 1.27 1.27)
					(thickness 0.15)
				)
			)
		)
		(property "Value" "TPS566231P"
			(at 309.88 68.58 0)
			(effects
				(font
					(size 1.27 1.27)
					(thickness 0.15)
				)
				(justify left bottom)
				(hide yes)
			)
		)
		(property "Footprint" "antmicro-footprints:VQFN-HR-9_2x1.5mm"
			(at 309.88 71.12 0)
			(effects
				(font
					(size 1.27 1.27)
					(thickness 0.15)
				)
				(justify left bottom)
				(hide yes)
			)
		)
		(property "Datasheet" "https://www.ti.com/lit/ds/symlink/tps566231.pdf"
			(at 309.88 73.66 0)
			(effects
				(font
					(size 1.27 1.27)
					(thickness 0.15)
				)
				(justify left bottom)
				(hide yes)
			)
		)
		(property "Description" "Switching Voltage Regulators 3-V to 18-V, 6-A synchronous buck converter"
			(at 309.88 86.36 0)
			(effects
				(font
					(size 1.27 1.27)
				)
				(justify left bottom)
				(hide yes)
			)
		)
		(property "Manufacturer" "Texas Instruments"
			(at 309.88 76.2 0)
			(effects
				(font
					(size 1.27 1.27)
					(thickness 0.15)
				)
				(justify left bottom)
				(hide yes)
			)
		)
		(property "MPN" "TPS566231PRQFR"
			(at 285.75 59.69 0)
			(effects
				(font
					(size 1.27 1.27)
					(thickness 0.15)
				)
			)
		)
		(property "Author" "Antmicro"
			(at 309.88 81.28 0)
			(effects
				(font
					(size 1.27 1.27)
					(thickness 0.15)
				)
				(justify left bottom)
				(hide yes)
			)
		)
		(property "License" "Apache-2.0"
			(at 309.88 83.82 0)
			(effects
				(font
					(size 1.27 1.27)
					(thickness 0.15)
				)
				(justify left bottom)
				(hide yes)
			)
		)
		(pin "1"
		)
		(pin "2"
		)
		(pin "3"
		)
		(pin "9"
		)
		(pin "5"
		)
		(pin "6"
		)
		(pin "8"
		)
		(pin "4"
		)
		(pin "7"
		)
		(instances
			(project "thunderbolt-to-10gbe-adapter"
				(path ""
					(reference "U10")
					(unit 1)
				)
			)
		)
	)
	(symbol
		(lib_id "antmicropower:GND")
		(at 354.33 43.18 0)
		(unit 1)
		(exclude_from_sim no)
		(in_bom yes)
		(on_board yes)
		(dnp no)
		(property "Reference" "#PWR0193"
			(at 363.22 45.72 0)
			(effects
				(font
					(size 1.27 1.27)
					(thickness 0.15)
				)
				(justify left bottom)
				(hide yes)
			)
		)
		(property "Value" "GND"
			(at 354.33 46.99 0)
			(effects
				(font
					(size 1.27 1.27)
					(thickness 0.15)
				)
			)
		)
		(property "Footprint" ""
			(at 363.22 50.8 0)
			(effects
				(font
					(size 1.27 1.27)
					(thickness 0.15)
				)
				(justify left bottom)
				(hide yes)
			)
		)
		(property "Datasheet" ""
			(at 363.22 55.88 0)
			(effects
				(font
					(size 1.27 1.27)
					(thickness 0.15)
				)
				(justify left bottom)
				(hide yes)
			)
		)
		(property "Description" ""
			(at 354.33 43.18 0)
			(effects
				(font
					(size 1.27 1.27)
				)
				(hide yes)
			)
		)
		(property "Author" "Antmicro"
			(at 363.22 50.8 0)
			(effects
				(font
					(size 1.27 1.27)
					(thickness 0.15)
				)
				(justify left bottom)
				(hide yes)
			)
		)
		(property "License" "Apache-2.0"
			(at 363.22 53.34 0)
			(effects
				(font
					(size 1.27 1.27)
					(thickness 0.15)
				)
				(justify left bottom)
				(hide yes)
			)
		)
		(pin "1"
		)
		(instances
			(project "thunderbolt-to-10gbe-adapter"
				(path ""
					(reference "#PWR0193")
					(unit 1)
				)
			)
		)
	)
	(symbol
		(lib_id "antmicroCapacitors0402:C_100n_0402")
		(at 307.34 144.78 270)
		(mirror x)
		(unit 1)
		(exclude_from_sim no)
		(in_bom yes)
		(on_board yes)
		(dnp no)
		(property "Reference" "C127"
			(at 309.118 141.224 90)
			(effects
				(font
					(size 1.27 1.27)
					(thickness 0.15)
				)
				(justify left)
			)
		)
		(property "Value" "C_100n_0402"
			(at 297.18 124.46 0)
			(effects
				(font
					(size 1.27 1.27)
					(thickness 0.15)
				)
				(justify left bottom)
				(hide yes)
			)
		)
		(property "Footprint" "antmicro-footprints:C_0402_1005Metric"
			(at 294.64 124.46 0)
			(effects
				(font
					(size 1.27 1.27)
					(thickness 0.15)
				)
				(justify left bottom)
				(hide yes)
			)
		)
		(property "Datasheet" "https://www.murata.com/products/productdetail?partno=GRM155R61H104KE14%23"
			(at 292.1 124.46 0)
			(effects
				(font
					(size 1.27 1.27)
					(thickness 0.15)
				)
				(justify left bottom)
				(hide yes)
			)
		)
		(property "Description" "SMD Multilayer Ceramic Capacitor, 0.1 µF, 50 V, 0402 [1005 Metric], ± 10%, X5R, GRM Series"
			(at 274.32 124.46 0)
			(effects
				(font
					(size 1.27 1.27)
				)
				(justify left bottom)
				(hide yes)
			)
		)
		(property "MPN" "GRM155R61H104KE14D"
			(at 289.56 124.46 0)
			(effects
				(font
					(size 1.27 1.27)
					(thickness 0.15)
				)
				(justify left bottom)
				(hide yes)
			)
		)
		(property "Manufacturer" "Murata"
			(at 287.02 124.46 0)
			(effects
				(font
					(size 1.27 1.27)
					(thickness 0.15)
				)
				(justify left bottom)
				(hide yes)
			)
		)
		(property "License" "Apache-2.0"
			(at 284.48 124.46 0)
			(effects
				(font
					(size 1.27 1.27)
					(thickness 0.15)
				)
				(justify left bottom)
				(hide yes)
			)
		)
		(property "Author" "Antmicro"
			(at 281.94 124.46 0)
			(effects
				(font
					(size 1.27 1.27)
					(thickness 0.15)
				)
				(justify left bottom)
				(hide yes)
			)
		)
		(property "Val" "100n"
			(at 309.118 143.764 90)
			(effects
				(font
					(size 1.27 1.27)
					(thickness 0.15)
				)
				(justify left)
			)
		)
		(property "Voltage" "50V"
			(at 279.4 124.46 0)
			(effects
				(font
					(size 1.27 1.27)
				)
				(justify left bottom)
				(hide yes)
			)
		)
		(property "Dielectric" "X5R"
			(at 276.86 124.46 0)
			(effects
				(font
					(size 1.27 1.27)
				)
				(justify left bottom)
				(hide yes)
			)
		)
		(pin "1"
		)
		(pin "2"
		)
		(instances
			(project "thunderbolt-to-10gbe-adapter"
				(path ""
					(reference "C127")
					(unit 1)
				)
			)
		)
	)
	(symbol
		(lib_id "antmicroCapacitors0603:C_22u_16V_0603")
		(at 227.33 114.3 270)
		(mirror x)
		(unit 1)
		(exclude_from_sim no)
		(in_bom yes)
		(on_board yes)
		(dnp no)
		(property "Reference" "C111"
			(at 225.552 110.49 90)
			(effects
				(font
					(size 1.27 1.27)
					(thickness 0.15)
				)
				(justify right)
			)
		)
		(property "Value" "C_22u_16V_0603"
			(at 217.17 93.98 0)
			(effects
				(font
					(size 1.27 1.27)
					(thickness 0.15)
				)
				(justify left bottom)
				(hide yes)
			)
		)
		(property "Footprint" "antmicro-footprints:C_0603_1608Metric_EIA"
			(at 214.63 93.98 0)
			(effects
				(font
					(size 1.27 1.27)
					(thickness 0.15)
				)
				(justify left bottom)
				(hide yes)
			)
		)
		(property "Datasheet" "https://product.samsungsem.com/mlcc/CL10A226MO7JZN.do"
			(at 212.09 93.98 0)
			(effects
				(font
					(size 1.27 1.27)
					(thickness 0.15)
				)
				(justify left bottom)
				(hide yes)
			)
		)
		(property "Description" "SMD Multilayer Ceramic Capacitor"
			(at 227.33 114.3 0)
			(effects
				(font
					(size 1.27 1.27)
				)
				(hide yes)
			)
		)
		(property "MPN" "CL10A226MO7JZNC"
			(at 209.55 93.98 0)
			(effects
				(font
					(size 1.27 1.27)
					(thickness 0.15)
				)
				(justify left bottom)
				(hide yes)
			)
		)
		(property "Manufacturer" "Samsung Electro-Mechanics"
			(at 207.01 93.98 0)
			(effects
				(font
					(size 1.27 1.27)
					(thickness 0.15)
				)
				(justify left bottom)
				(hide yes)
			)
		)
		(property "License" "Apache-2.0"
			(at 204.47 93.98 0)
			(effects
				(font
					(size 1.27 1.27)
					(thickness 0.15)
				)
				(justify left bottom)
				(hide yes)
			)
		)
		(property "Author" "Antmicro"
			(at 201.93 93.98 0)
			(effects
				(font
					(size 1.27 1.27)
					(thickness 0.15)
				)
				(justify left bottom)
				(hide yes)
			)
		)
		(property "Val" "22u"
			(at 225.552 113.03 90)
			(effects
				(font
					(size 1.27 1.27)
					(thickness 0.15)
				)
				(justify right)
			)
		)
		(property "Voltage" "16V"
			(at 224.79 114.2935 90)
			(effects
				(font
					(size 1.27 1.27)
				)
				(justify right)
				(hide yes)
			)
		)
		(property "Dielectric" ""
			(at 196.85 93.98 0)
			(effects
				(font
					(size 1.27 1.27)
				)
				(justify left bottom)
				(hide yes)
			)
		)
		(pin "2"
		)
		(pin "1"
		)
		(instances
			(project "thunderbolt-to-10gbe-adapter"
				(path ""
					(reference "C111")
					(unit 1)
				)
			)
		)
	)
	(symbol
		(lib_id "antmicroTestPoints:TP_0.75mm_SMD")
		(at 391.16 236.22 0)
		(unit 1)
		(exclude_from_sim no)
		(in_bom no)
		(on_board yes)
		(dnp no)
		(fields_autoplaced yes)
		(property "Reference" "TP18"
			(at 396.24 236.22 0)
			(effects
				(font
					(size 1.27 1.27)
					(thickness 0.15)
				)
				(justify left)
			)
		)
		(property "Value" "TP_0.75mm_SMD"
			(at 401.32 240.03 0)
			(effects
				(font
					(size 1.27 1.27)
					(thickness 0.15)
				)
				(justify left bottom)
				(hide yes)
			)
		)
		(property "Footprint" "antmicro-footprints:TP_SMD_0.75mm"
			(at 401.32 242.57 0)
			(effects
				(font
					(size 1.27 1.27)
					(thickness 0.15)
				)
				(justify left bottom)
				(hide yes)
			)
		)
		(property "Datasheet" ""
			(at 408.94 248.92 0)
			(effects
				(font
					(size 1.27 1.27)
					(thickness 0.15)
				)
				(justify left bottom)
				(hide yes)
			)
		)
		(property "Description" "SMT test point"
			(at 401.955 250.19 0)
			(effects
				(font
					(size 1.27 1.27)
				)
				(justify left bottom)
				(hide yes)
			)
		)
		(property "MPN" ""
			(at 401.955 247.65 0)
			(effects
				(font
					(size 1.27 1.27)
					(thickness 0.15)
				)
				(justify left bottom)
				(hide yes)
			)
		)
		(property "Manufacturer" ""
			(at 401.955 242.57 0)
			(effects
				(font
					(size 1.27 1.27)
					(thickness 0.15)
				)
				(justify left bottom)
				(hide yes)
			)
		)
		(property "Author" "Antmicro"
			(at 401.32 245.11 0)
			(effects
				(font
					(size 1.27 1.27)
					(thickness 0.15)
				)
				(justify left bottom)
				(hide yes)
			)
		)
		(property "License" "Apache-2.0"
			(at 401.32 247.65 0)
			(effects
				(font
					(size 1.27 1.27)
					(thickness 0.15)
				)
				(justify left bottom)
				(hide yes)
			)
		)
		(pin "1"
		)
		(instances
			(project "thunderbolt-to-10gbe-adapter"
				(path ""
					(reference "TP18")
					(unit 1)
				)
			)
		)
	)
	(symbol
		(lib_id "antmicroCapacitors0603:C_22u_16V_0603")
		(at 354.33 190.5 90)
		(unit 1)
		(exclude_from_sim no)
		(in_bom yes)
		(on_board yes)
		(dnp no)
		(property "Reference" "C143"
			(at 356.108 186.69 90)
			(effects
				(font
					(size 1.27 1.27)
					(thickness 0.15)
				)
				(justify right)
			)
		)
		(property "Value" "C_22u_16V_0603"
			(at 364.49 170.18 0)
			(effects
				(font
					(size 1.27 1.27)
					(thickness 0.15)
				)
				(justify left bottom)
				(hide yes)
			)
		)
		(property "Footprint" "antmicro-footprints:C_0603_1608Metric_EIA"
			(at 367.03 170.18 0)
			(effects
				(font
					(size 1.27 1.27)
					(thickness 0.15)
				)
				(justify left bottom)
				(hide yes)
			)
		)
		(property "Datasheet" "https://product.samsungsem.com/mlcc/CL10A226MO7JZN.do"
			(at 369.57 170.18 0)
			(effects
				(font
					(size 1.27 1.27)
					(thickness 0.15)
				)
				(justify left bottom)
				(hide yes)
			)
		)
		(property "Description" "SMD Multilayer Ceramic Capacitor"
			(at 354.33 190.5 0)
			(effects
				(font
					(size 1.27 1.27)
				)
				(hide yes)
			)
		)
		(property "MPN" "CL10A226MO7JZNC"
			(at 372.11 170.18 0)
			(effects
				(font
					(size 1.27 1.27)
					(thickness 0.15)
				)
				(justify left bottom)
				(hide yes)
			)
		)
		(property "Manufacturer" "Samsung Electro-Mechanics"
			(at 374.65 170.18 0)
			(effects
				(font
					(size 1.27 1.27)
					(thickness 0.15)
				)
				(justify left bottom)
				(hide yes)
			)
		)
		(property "License" "Apache-2.0"
			(at 377.19 170.18 0)
			(effects
				(font
					(size 1.27 1.27)
					(thickness 0.15)
				)
				(justify left bottom)
				(hide yes)
			)
		)
		(property "Author" "Antmicro"
			(at 379.73 170.18 0)
			(effects
				(font
					(size 1.27 1.27)
					(thickness 0.15)
				)
				(justify left bottom)
				(hide yes)
			)
		)
		(property "Val" "22u"
			(at 356.108 189.23 90)
			(effects
				(font
					(size 1.27 1.27)
					(thickness 0.15)
				)
				(justify right)
			)
		)
		(property "Voltage" "16V"
			(at 356.87 190.4935 90)
			(effects
				(font
					(size 1.27 1.27)
				)
				(justify right)
				(hide yes)
			)
		)
		(property "Dielectric" ""
			(at 384.81 170.18 0)
			(effects
				(font
					(size 1.27 1.27)
				)
				(justify left bottom)
				(hide yes)
			)
		)
		(pin "2"
		)
		(pin "1"
		)
		(instances
			(project "thunderbolt-to-10gbe-adapter"
				(path ""
					(reference "C143")
					(unit 1)
				)
			)
		)
	)
	(symbol
		(lib_id "antmicropower:GND")
		(at 237.49 81.28 0)
		(unit 1)
		(exclude_from_sim no)
		(in_bom yes)
		(on_board yes)
		(dnp no)
		(property "Reference" "#PWR0166"
			(at 246.38 83.82 0)
			(effects
				(font
					(size 1.27 1.27)
					(thickness 0.15)
				)
				(justify left bottom)
				(hide yes)
			)
		)
		(property "Value" "GND"
			(at 237.49 85.09 0)
			(effects
				(font
					(size 1.27 1.27)
					(thickness 0.15)
				)
			)
		)
		(property "Footprint" ""
			(at 246.38 88.9 0)
			(effects
				(font
					(size 1.27 1.27)
					(thickness 0.15)
				)
				(justify left bottom)
				(hide yes)
			)
		)
		(property "Datasheet" ""
			(at 246.38 93.98 0)
			(effects
				(font
					(size 1.27 1.27)
					(thickness 0.15)
				)
				(justify left bottom)
				(hide yes)
			)
		)
		(property "Description" ""
			(at 237.49 81.28 0)
			(effects
				(font
					(size 1.27 1.27)
				)
				(hide yes)
			)
		)
		(property "Author" "Antmicro"
			(at 246.38 88.9 0)
			(effects
				(font
					(size 1.27 1.27)
					(thickness 0.15)
				)
				(justify left bottom)
				(hide yes)
			)
		)
		(property "License" "Apache-2.0"
			(at 246.38 91.44 0)
			(effects
				(font
					(size 1.27 1.27)
					(thickness 0.15)
				)
				(justify left bottom)
				(hide yes)
			)
		)
		(pin "1"
		)
		(instances
			(project "thunderbolt-to-10gbe-adapter"
				(path ""
					(reference "#PWR0166")
					(unit 1)
				)
			)
		)
	)
	(symbol
		(lib_id "antmicroCapacitors0603:C_22u_16V_0603")
		(at 217.17 114.3 270)
		(mirror x)
		(unit 1)
		(exclude_from_sim no)
		(in_bom yes)
		(on_board yes)
		(dnp no)
		(property "Reference" "C106"
			(at 215.138 110.49 90)
			(effects
				(font
					(size 1.27 1.27)
					(thickness 0.15)
				)
				(justify right)
			)
		)
		(property "Value" "C_22u_16V_0603"
			(at 207.01 93.98 0)
			(effects
				(font
					(size 1.27 1.27)
					(thickness 0.15)
				)
				(justify left bottom)
				(hide yes)
			)
		)
		(property "Footprint" "antmicro-footprints:C_0603_1608Metric_EIA"
			(at 204.47 93.98 0)
			(effects
				(font
					(size 1.27 1.27)
					(thickness 0.15)
				)
				(justify left bottom)
				(hide yes)
			)
		)
		(property "Datasheet" "https://product.samsungsem.com/mlcc/CL10A226MO7JZN.do"
			(at 201.93 93.98 0)
			(effects
				(font
					(size 1.27 1.27)
					(thickness 0.15)
				)
				(justify left bottom)
				(hide yes)
			)
		)
		(property "Description" "SMD Multilayer Ceramic Capacitor"
			(at 217.17 114.3 0)
			(effects
				(font
					(size 1.27 1.27)
				)
				(hide yes)
			)
		)
		(property "MPN" "CL10A226MO7JZNC"
			(at 199.39 93.98 0)
			(effects
				(font
					(size 1.27 1.27)
					(thickness 0.15)
				)
				(justify left bottom)
				(hide yes)
			)
		)
		(property "Manufacturer" "Samsung Electro-Mechanics"
			(at 196.85 93.98 0)
			(effects
				(font
					(size 1.27 1.27)
					(thickness 0.15)
				)
				(justify left bottom)
				(hide yes)
			)
		)
		(property "License" "Apache-2.0"
			(at 194.31 93.98 0)
			(effects
				(font
					(size 1.27 1.27)
					(thickness 0.15)
				)
				(justify left bottom)
				(hide yes)
			)
		)
		(property "Author" "Antmicro"
			(at 191.77 93.98 0)
			(effects
				(font
					(size 1.27 1.27)
					(thickness 0.15)
				)
				(justify left bottom)
				(hide yes)
			)
		)
		(property "Val" "22u"
			(at 215.138 113.03 90)
			(effects
				(font
					(size 1.27 1.27)
					(thickness 0.15)
				)
				(justify right)
			)
		)
		(property "Voltage" "16V"
			(at 214.63 114.2935 90)
			(effects
				(font
					(size 1.27 1.27)
				)
				(justify right)
				(hide yes)
			)
		)
		(property "Dielectric" ""
			(at 186.69 93.98 0)
			(effects
				(font
					(size 1.27 1.27)
				)
				(justify left bottom)
				(hide yes)
			)
		)
		(pin "2"
		)
		(pin "1"
		)
		(instances
			(project "thunderbolt-to-10gbe-adapter"
				(path ""
					(reference "C106")
					(unit 1)
				)
			)
		)
	)
	(symbol
		(lib_id "antmicropower:GND")
		(at 344.17 81.28 0)
		(unit 1)
		(exclude_from_sim no)
		(in_bom yes)
		(on_board yes)
		(dnp no)
		(property "Reference" "#PWR0189"
			(at 353.06 83.82 0)
			(effects
				(font
					(size 1.27 1.27)
					(thickness 0.15)
				)
				(justify left bottom)
				(hide yes)
			)
		)
		(property "Value" "GND"
			(at 344.17 85.09 0)
			(effects
				(font
					(size 1.27 1.27)
					(thickness 0.15)
				)
			)
		)
		(property "Footprint" ""
			(at 353.06 88.9 0)
			(effects
				(font
					(size 1.27 1.27)
					(thickness 0.15)
				)
				(justify left bottom)
				(hide yes)
			)
		)
		(property "Datasheet" ""
			(at 353.06 93.98 0)
			(effects
				(font
					(size 1.27 1.27)
					(thickness 0.15)
				)
				(justify left bottom)
				(hide yes)
			)
		)
		(property "Description" ""
			(at 344.17 81.28 0)
			(effects
				(font
					(size 1.27 1.27)
				)
				(hide yes)
			)
		)
		(property "Author" "Antmicro"
			(at 353.06 88.9 0)
			(effects
				(font
					(size 1.27 1.27)
					(thickness 0.15)
				)
				(justify left bottom)
				(hide yes)
			)
		)
		(property "License" "Apache-2.0"
			(at 353.06 91.44 0)
			(effects
				(font
					(size 1.27 1.27)
					(thickness 0.15)
				)
				(justify left bottom)
				(hide yes)
			)
		)
		(pin "1"
		)
		(instances
			(project "thunderbolt-to-10gbe-adapter"
				(path ""
					(reference "#PWR0189")
					(unit 1)
				)
			)
		)
	)
	(symbol
		(lib_id "antmicropower:GND")
		(at 344.17 157.48 0)
		(unit 1)
		(exclude_from_sim no)
		(in_bom yes)
		(on_board yes)
		(dnp no)
		(property "Reference" "#PWR0191"
			(at 353.06 160.02 0)
			(effects
				(font
					(size 1.27 1.27)
					(thickness 0.15)
				)
				(justify left bottom)
				(hide yes)
			)
		)
		(property "Value" "GND"
			(at 344.17 161.29 0)
			(effects
				(font
					(size 1.27 1.27)
					(thickness 0.15)
				)
			)
		)
		(property "Footprint" ""
			(at 353.06 165.1 0)
			(effects
				(font
					(size 1.27 1.27)
					(thickness 0.15)
				)
				(justify left bottom)
				(hide yes)
			)
		)
		(property "Datasheet" ""
			(at 353.06 170.18 0)
			(effects
				(font
					(size 1.27 1.27)
					(thickness 0.15)
				)
				(justify left bottom)
				(hide yes)
			)
		)
		(property "Description" ""
			(at 344.17 157.48 0)
			(effects
				(font
					(size 1.27 1.27)
				)
				(hide yes)
			)
		)
		(property "Author" "Antmicro"
			(at 353.06 165.1 0)
			(effects
				(font
					(size 1.27 1.27)
					(thickness 0.15)
				)
				(justify left bottom)
				(hide yes)
			)
		)
		(property "License" "Apache-2.0"
			(at 353.06 167.64 0)
			(effects
				(font
					(size 1.27 1.27)
					(thickness 0.15)
				)
				(justify left bottom)
				(hide yes)
			)
		)
		(pin "1"
		)
		(instances
			(project "thunderbolt-to-10gbe-adapter"
				(path ""
					(reference "#PWR0191")
					(unit 1)
				)
			)
		)
	)
	(symbol
		(lib_id "antmicropower:PWR_FLAG")
		(at 391.16 99.06 0)
		(unit 1)
		(exclude_from_sim no)
		(in_bom yes)
		(on_board yes)
		(dnp no)
		(property "Reference" "#FLG021"
			(at 391.16 97.155 0)
			(effects
				(font
					(size 1.27 1.27)
				)
				(hide yes)
			)
		)
		(property "Value" "PWR_FLAG"
			(at 391.16 95.25 0)
			(effects
				(font
					(size 1.27 1.27)
				)
			)
		)
		(property "Footprint" ""
			(at 391.16 99.06 0)
			(effects
				(font
					(size 1.27 1.27)
				)
				(hide yes)
			)
		)
		(property "Datasheet" ""
			(at 391.16 99.06 0)
			(effects
				(font
					(size 1.27 1.27)
				)
				(hide yes)
			)
		)
		(property "Description" ""
			(at 391.16 99.06 0)
			(effects
				(font
					(size 1.27 1.27)
				)
				(hide yes)
			)
		)
		(pin "1"
		)
		(instances
			(project "thunderbolt-to-10gbe-adapter"
				(path ""
					(reference "#FLG021")
					(unit 1)
				)
			)
		)
	)
	(symbol
		(lib_id "antmicroTransistorsBipolarSingle:DTC014T_SOT-416")
		(at 246.38 238.76 0)
		(unit 1)
		(exclude_from_sim no)
		(in_bom yes)
		(on_board yes)
		(dnp no)
		(property "Reference" "Q4"
			(at 255.778 240.03 0)
			(effects
				(font
					(size 1.27 1.27)
					(thickness 0.15)
				)
				(justify left)
			)
		)
		(property "Value" "DTC014T_SOT-416"
			(at 271.78 246.38 0)
			(effects
				(font
					(size 1.27 1.27)
					(thickness 0.15)
				)
				(justify left bottom)
				(hide yes)
			)
		)
		(property "Footprint" "antmicro-footprints:SOT-416"
			(at 271.78 248.92 0)
			(effects
				(font
					(size 1.27 1.27)
					(thickness 0.15)
				)
				(justify left bottom)
				(hide yes)
			)
		)
		(property "Datasheet" "https://www.rohm.com/datasheet?p=DTC014TEB&dist=Mouser&media=referral&source=mouser.com&campaign=Mouser"
			(at 271.78 251.46 0)
			(effects
				(font
					(size 1.27 1.27)
					(thickness 0.15)
				)
				(justify left bottom)
				(hide yes)
			)
		)
		(property "Description" "Bipolar (BJT) Single Transistor with built-in base resistor, NPN, 50V, 100mA, 150mW, SOT-416FL, Surface Mount"
			(at 271.78 264.16 0)
			(effects
				(font
					(size 1.27 1.27)
				)
				(justify left bottom)
				(hide yes)
			)
		)
		(property "Manufacturer" "ROHM Semiconductor"
			(at 271.78 254 0)
			(effects
				(font
					(size 1.27 1.27)
					(thickness 0.15)
				)
				(justify left bottom)
				(hide yes)
			)
		)
		(property "MPN" "DTC014TEBTL"
			(at 255.778 242.57 0)
			(effects
				(font
					(size 1.27 1.27)
					(thickness 0.15)
				)
				(justify left)
			)
		)
		(property "Author" "Antmicro"
			(at 271.78 259.08 0)
			(effects
				(font
					(size 1.27 1.27)
					(thickness 0.15)
				)
				(justify left bottom)
				(hide yes)
			)
		)
		(property "License" "Apache-2.0"
			(at 271.78 261.62 0)
			(effects
				(font
					(size 1.27 1.27)
					(thickness 0.15)
				)
				(justify left bottom)
				(hide yes)
			)
		)
		(pin "1"
		)
		(pin "2"
		)
		(pin "3"
		)
		(instances
			(project "thunderbolt-to-10gbe-adapter"
				(path ""
					(reference "Q4")
					(unit 1)
				)
			)
		)
	)
	(symbol
		(lib_id "antmicroLEDIndicationDiscrete:LED_G_0603_LG_L29K-G2J1-24-Z")
		(at 177.8 223.52 90)
		(unit 1)
		(exclude_from_sim no)
		(in_bom yes)
		(on_board yes)
		(dnp no)
		(property "Reference" "D6"
			(at 179.07 219.71 90)
			(effects
				(font
					(size 1.27 1.27)
					(thickness 0.15)
				)
				(justify right)
			)
		)
		(property "Value" "LED_G_0603_LG_L29K-G2J1-24-Z"
			(at 185.42 203.2 0)
			(effects
				(font
					(size 1.27 1.27)
					(thickness 0.15)
				)
				(justify left bottom)
				(hide yes)
			)
		)
		(property "Footprint" "antmicro-footprints:LED_0603_1608Metric_G"
			(at 187.96 203.2 0)
			(effects
				(font
					(size 1.27 1.27)
					(thickness 0.15)
				)
				(justify left bottom)
				(hide yes)
			)
		)
		(property "Datasheet" "https://look.ams-osram.com/m/19ee86b3ae0ee95b/original/LG-L29K.pdf"
			(at 190.5 203.2 0)
			(effects
				(font
					(size 1.27 1.27)
					(thickness 0.15)
				)
				(justify left bottom)
				(hide yes)
			)
		)
		(property "Description" "LED, Green, SMD, 0603, 20 mA, 1.7 V, 570 nm"
			(at 177.8 223.52 0)
			(effects
				(font
					(size 1.27 1.27)
				)
				(hide yes)
			)
		)
		(property "MPN" "LG L29K-G2J1-24-Z"
			(at 193.04 203.2 0)
			(effects
				(font
					(size 1.27 1.27)
					(thickness 0.15)
				)
				(justify left bottom)
				(hide yes)
			)
		)
		(property "Manufacturer" "OSRAM"
			(at 195.58 203.2 0)
			(effects
				(font
					(size 1.27 1.27)
					(thickness 0.15)
				)
				(justify left bottom)
				(hide yes)
			)
		)
		(property "Color" "Green"
			(at 179.07 222.2499 90)
			(effects
				(font
					(size 1.27 1.27)
				)
				(justify right)
			)
		)
		(property "Author" "Antmicro"
			(at 198.12 203.2 0)
			(effects
				(font
					(size 1.27 1.27)
					(thickness 0.15)
				)
				(justify left bottom)
				(hide yes)
			)
		)
		(property "License" "Apache-2.0"
			(at 200.66 203.2 0)
			(effects
				(font
					(size 1.27 1.27)
					(thickness 0.15)
				)
				(justify left bottom)
				(hide yes)
			)
		)
		(pin "2"
		)
		(pin "1"
		)
		(instances
			(project "thunderbolt-to-10gbe-adapter"
				(path ""
					(reference "D6")
					(unit 1)
				)
			)
		)
	)
	(symbol
		(lib_id "antmicropower:GND")
		(at 374.65 119.38 0)
		(unit 1)
		(exclude_from_sim no)
		(in_bom yes)
		(on_board yes)
		(dnp no)
		(property "Reference" "#PWR0205"
			(at 383.54 121.92 0)
			(effects
				(font
					(size 1.27 1.27)
					(thickness 0.15)
				)
				(justify left bottom)
				(hide yes)
			)
		)
		(property "Value" "GND"
			(at 374.65 123.19 0)
			(effects
				(font
					(size 1.27 1.27)
					(thickness 0.15)
				)
			)
		)
		(property "Footprint" ""
			(at 383.54 127 0)
			(effects
				(font
					(size 1.27 1.27)
					(thickness 0.15)
				)
				(justify left bottom)
				(hide yes)
			)
		)
		(property "Datasheet" ""
			(at 383.54 132.08 0)
			(effects
				(font
					(size 1.27 1.27)
					(thickness 0.15)
				)
				(justify left bottom)
				(hide yes)
			)
		)
		(property "Description" ""
			(at 374.65 119.38 0)
			(effects
				(font
					(size 1.27 1.27)
				)
				(hide yes)
			)
		)
		(property "Author" "Antmicro"
			(at 383.54 127 0)
			(effects
				(font
					(size 1.27 1.27)
					(thickness 0.15)
				)
				(justify left bottom)
				(hide yes)
			)
		)
		(property "License" "Apache-2.0"
			(at 383.54 129.54 0)
			(effects
				(font
					(size 1.27 1.27)
					(thickness 0.15)
				)
				(justify left bottom)
				(hide yes)
			)
		)
		(pin "1"
		)
		(instances
			(project "thunderbolt-to-10gbe-adapter"
				(path ""
					(reference "#PWR0205")
					(unit 1)
				)
			)
		)
	)
	(symbol
		(lib_id "antmicropower:GND")
		(at 237.49 195.58 0)
		(unit 1)
		(exclude_from_sim no)
		(in_bom yes)
		(on_board yes)
		(dnp no)
		(property "Reference" "#PWR0169"
			(at 246.38 198.12 0)
			(effects
				(font
					(size 1.27 1.27)
					(thickness 0.15)
				)
				(justify left bottom)
				(hide yes)
			)
		)
		(property "Value" "GND"
			(at 237.49 199.39 0)
			(effects
				(font
					(size 1.27 1.27)
					(thickness 0.15)
				)
			)
		)
		(property "Footprint" ""
			(at 246.38 203.2 0)
			(effects
				(font
					(size 1.27 1.27)
					(thickness 0.15)
				)
				(justify left bottom)
				(hide yes)
			)
		)
		(property "Datasheet" ""
			(at 246.38 208.28 0)
			(effects
				(font
					(size 1.27 1.27)
					(thickness 0.15)
				)
				(justify left bottom)
				(hide yes)
			)
		)
		(property "Description" ""
			(at 237.49 195.58 0)
			(effects
				(font
					(size 1.27 1.27)
				)
				(hide yes)
			)
		)
		(property "Author" "Antmicro"
			(at 246.38 203.2 0)
			(effects
				(font
					(size 1.27 1.27)
					(thickness 0.15)
				)
				(justify left bottom)
				(hide yes)
			)
		)
		(property "License" "Apache-2.0"
			(at 246.38 205.74 0)
			(effects
				(font
					(size 1.27 1.27)
					(thickness 0.15)
				)
				(justify left bottom)
				(hide yes)
			)
		)
		(pin "1"
		)
		(instances
			(project "thunderbolt-to-10gbe-adapter"
				(path ""
					(reference "#PWR0169")
					(unit 1)
				)
			)
		)
	)
	(symbol
		(lib_id "antmicropower:GND")
		(at 374.65 195.58 0)
		(unit 1)
		(exclude_from_sim no)
		(in_bom yes)
		(on_board yes)
		(dnp no)
		(property "Reference" "#PWR0207"
			(at 383.54 198.12 0)
			(effects
				(font
					(size 1.27 1.27)
					(thickness 0.15)
				)
				(justify left bottom)
				(hide yes)
			)
		)
		(property "Value" "GND"
			(at 374.65 199.39 0)
			(effects
				(font
					(size 1.27 1.27)
					(thickness 0.15)
				)
			)
		)
		(property "Footprint" ""
			(at 383.54 203.2 0)
			(effects
				(font
					(size 1.27 1.27)
					(thickness 0.15)
				)
				(justify left bottom)
				(hide yes)
			)
		)
		(property "Datasheet" ""
			(at 383.54 208.28 0)
			(effects
				(font
					(size 1.27 1.27)
					(thickness 0.15)
				)
				(justify left bottom)
				(hide yes)
			)
		)
		(property "Description" ""
			(at 374.65 195.58 0)
			(effects
				(font
					(size 1.27 1.27)
				)
				(hide yes)
			)
		)
		(property "Author" "Antmicro"
			(at 383.54 203.2 0)
			(effects
				(font
					(size 1.27 1.27)
					(thickness 0.15)
				)
				(justify left bottom)
				(hide yes)
			)
		)
		(property "License" "Apache-2.0"
			(at 383.54 205.74 0)
			(effects
				(font
					(size 1.27 1.27)
					(thickness 0.15)
				)
				(justify left bottom)
				(hide yes)
			)
		)
		(pin "1"
		)
		(instances
			(project "thunderbolt-to-10gbe-adapter"
				(path ""
					(reference "#PWR0207")
					(unit 1)
				)
			)
		)
	)
	(symbol
		(lib_id "antmicropower:GND")
		(at 332.74 119.38 0)
		(unit 1)
		(exclude_from_sim no)
		(in_bom yes)
		(on_board yes)
		(dnp no)
		(property "Reference" "#PWR0185"
			(at 341.63 121.92 0)
			(effects
				(font
					(size 1.27 1.27)
					(thickness 0.15)
				)
				(justify left bottom)
				(hide yes)
			)
		)
		(property "Value" "GND"
			(at 332.74 123.19 0)
			(effects
				(font
					(size 1.27 1.27)
					(thickness 0.15)
				)
			)
		)
		(property "Footprint" ""
			(at 341.63 127 0)
			(effects
				(font
					(size 1.27 1.27)
					(thickness 0.15)
				)
				(justify left bottom)
				(hide yes)
			)
		)
		(property "Datasheet" ""
			(at 341.63 132.08 0)
			(effects
				(font
					(size 1.27 1.27)
					(thickness 0.15)
				)
				(justify left bottom)
				(hide yes)
			)
		)
		(property "Description" ""
			(at 332.74 119.38 0)
			(effects
				(font
					(size 1.27 1.27)
				)
				(hide yes)
			)
		)
		(property "Author" "Antmicro"
			(at 341.63 127 0)
			(effects
				(font
					(size 1.27 1.27)
					(thickness 0.15)
				)
				(justify left bottom)
				(hide yes)
			)
		)
		(property "License" "Apache-2.0"
			(at 341.63 129.54 0)
			(effects
				(font
					(size 1.27 1.27)
					(thickness 0.15)
				)
				(justify left bottom)
				(hide yes)
			)
		)
		(pin "1"
		)
		(instances
			(project "thunderbolt-to-10gbe-adapter"
				(path ""
					(reference "#PWR0185")
					(unit 1)
				)
			)
		)
	)
	(symbol
		(lib_id "antmicroCapacitors0402:C_100n_0402")
		(at 374.65 190.5 90)
		(unit 1)
		(exclude_from_sim no)
		(in_bom yes)
		(on_board yes)
		(dnp no)
		(property "Reference" "C153"
			(at 376.428 186.69 90)
			(effects
				(font
					(size 1.27 1.27)
					(thickness 0.15)
				)
				(justify right)
			)
		)
		(property "Value" "C_100n_0402"
			(at 384.81 170.18 0)
			(effects
				(font
					(size 1.27 1.27)
					(thickness 0.15)
				)
				(justify left bottom)
				(hide yes)
			)
		)
		(property "Footprint" "antmicro-footprints:C_0402_1005Metric"
			(at 387.35 170.18 0)
			(effects
				(font
					(size 1.27 1.27)
					(thickness 0.15)
				)
				(justify left bottom)
				(hide yes)
			)
		)
		(property "Datasheet" "https://www.murata.com/products/productdetail?partno=GRM155R61H104KE14%23"
			(at 389.89 170.18 0)
			(effects
				(font
					(size 1.27 1.27)
					(thickness 0.15)
				)
				(justify left bottom)
				(hide yes)
			)
		)
		(property "Description" "SMD Multilayer Ceramic Capacitor, 0.1 µF, 50 V, 0402 [1005 Metric], ± 10%, X5R, GRM Series"
			(at 407.67 170.18 0)
			(effects
				(font
					(size 1.27 1.27)
				)
				(justify left bottom)
				(hide yes)
			)
		)
		(property "MPN" "GRM155R61H104KE14D"
			(at 392.43 170.18 0)
			(effects
				(font
					(size 1.27 1.27)
					(thickness 0.15)
				)
				(justify left bottom)
				(hide yes)
			)
		)
		(property "Manufacturer" "Murata"
			(at 394.97 170.18 0)
			(effects
				(font
					(size 1.27 1.27)
					(thickness 0.15)
				)
				(justify left bottom)
				(hide yes)
			)
		)
		(property "License" "Apache-2.0"
			(at 397.51 170.18 0)
			(effects
				(font
					(size 1.27 1.27)
					(thickness 0.15)
				)
				(justify left bottom)
				(hide yes)
			)
		)
		(property "Author" "Antmicro"
			(at 400.05 170.18 0)
			(effects
				(font
					(size 1.27 1.27)
					(thickness 0.15)
				)
				(justify left bottom)
				(hide yes)
			)
		)
		(property "Val" "100n"
			(at 376.428 189.23 90)
			(effects
				(font
					(size 1.27 1.27)
					(thickness 0.15)
				)
				(justify right)
			)
		)
		(property "Voltage" "50V"
			(at 402.59 170.18 0)
			(effects
				(font
					(size 1.27 1.27)
				)
				(justify left bottom)
				(hide yes)
			)
		)
		(property "Dielectric" "X5R"
			(at 405.13 170.18 0)
			(effects
				(font
					(size 1.27 1.27)
				)
				(justify left bottom)
				(hide yes)
			)
		)
		(pin "1"
		)
		(pin "2"
		)
		(instances
			(project "thunderbolt-to-10gbe-adapter"
				(path ""
					(reference "C153")
					(unit 1)
				)
			)
		)
	)
	(symbol
		(lib_id "antmicroResistors0603:R_0R_22.4A_0603")
		(at 379.73 25.4 0)
		(unit 1)
		(exclude_from_sim no)
		(in_bom yes)
		(on_board yes)
		(dnp no)
		(property "Reference" "R108"
			(at 379.73 24.13 0)
			(effects
				(font
					(size 1.27 1.27)
					(thickness 0.15)
				)
				(justify right)
			)
		)
		(property "Value" "R_0R_22.4A_0603"
			(at 394.97 30.48 0)
			(effects
				(font
					(size 1.27 1.27)
					(thickness 0.15)
				)
				(justify left bottom)
				(hide yes)
			)
		)
		(property "Footprint" "antmicro-footprints:R_0603_1608Metric"
			(at 394.97 35.56 0)
			(effects
				(font
					(size 1.27 1.27)
					(thickness 0.15)
				)
				(justify left bottom)
				(hide yes)
			)
		)
		(property "Datasheet" "https://fscdn.rohm.com/en/products/databook/datasheet/passive/resistor/chip_resistor/pmr-jpw-e.pdf"
			(at 394.97 38.1 0)
			(effects
				(font
					(size 1.27 1.27)
					(thickness 0.15)
				)
				(justify left bottom)
				(hide yes)
			)
		)
		(property "Description" "SMD Chip Resistor"
			(at 394.97 53.34 0)
			(effects
				(font
					(size 1.27 1.27)
				)
				(justify left bottom)
				(hide yes)
			)
		)
		(property "MPN" "PMR03EZPJ000"
			(at 394.97 40.64 0)
			(effects
				(font
					(size 1.27 1.27)
					(thickness 0.15)
				)
				(justify left bottom)
				(hide yes)
			)
		)
		(property "Manufacturer" "ROHM Semiconductor"
			(at 394.97 43.18 0)
			(effects
				(font
					(size 1.27 1.27)
					(thickness 0.15)
				)
				(justify left bottom)
				(hide yes)
			)
		)
		(property "Val" "0R"
			(at 384.81 24.13 0)
			(effects
				(font
					(size 1.27 1.27)
					(thickness 0.15)
				)
				(justify left)
			)
		)
		(property "Max. Curr." "22.4A"
			(at 382.27 27.94 0)
			(effects
				(font
					(size 1.27 1.27)
					(thickness 0.15)
				)
			)
		)
		(property "Author" "Antmicro"
			(at 394.97 48.26 0)
			(effects
				(font
					(size 1.27 1.27)
					(thickness 0.15)
				)
				(justify left bottom)
				(hide yes)
			)
		)
		(property "License" "Apache-2.0"
			(at 394.97 50.8 0)
			(effects
				(font
					(size 1.27 1.27)
					(thickness 0.15)
				)
				(justify left bottom)
				(hide yes)
			)
		)
		(property "Tolerance" "template_tolerance"
			(at 400.05 35.56 0)
			(effects
				(font
					(size 1.27 1.27)
				)
				(justify left bottom)
				(hide yes)
			)
		)
		(pin "1"
		)
		(pin "2"
		)
		(instances
			(project "thunderbolt-to-10gbe-adapter"
				(path ""
					(reference "R108")
					(unit 1)
				)
			)
		)
	)
	(symbol
		(lib_id "antmicropower:+1V0")
		(at 387.35 236.22 90)
		(unit 1)
		(exclude_from_sim no)
		(in_bom yes)
		(on_board yes)
		(dnp no)
		(fields_autoplaced yes)
		(property "Reference" "#PWR0211"
			(at 391.16 236.22 0)
			(effects
				(font
					(size 1.27 1.27)
				)
				(hide yes)
			)
		)
		(property "Value" "+1V0"
			(at 383.54 236.2199 90)
			(effects
				(font
					(size 1.27 1.27)
				)
				(justify left)
			)
		)
		(property "Footprint" ""
			(at 387.35 236.22 0)
			(effects
				(font
					(size 1.27 1.27)
				)
				(hide yes)
			)
		)
		(property "Datasheet" ""
			(at 387.35 236.22 0)
			(effects
				(font
					(size 1.27 1.27)
				)
				(hide yes)
			)
		)
		(property "Description" ""
			(at 387.35 236.22 0)
			(effects
				(font
					(size 1.27 1.27)
				)
				(hide yes)
			)
		)
		(pin "1"
		)
		(instances
			(project "thunderbolt-to-10gbe-adapter"
				(path ""
					(reference "#PWR0211")
					(unit 1)
				)
			)
		)
	)
	(symbol
		(lib_id "antmicroLEDIndicationDiscrete:LED_G_0603_LG_L29K-G2J1-24-Z")
		(at 304.8 228.6 90)
		(unit 1)
		(exclude_from_sim no)
		(in_bom yes)
		(on_board yes)
		(dnp no)
		(property "Reference" "D11"
			(at 306.07 224.79 90)
			(effects
				(font
					(size 1.27 1.27)
					(thickness 0.15)
				)
				(justify right)
			)
		)
		(property "Value" "LED_G_0603_LG_L29K-G2J1-24-Z"
			(at 312.42 208.28 0)
			(effects
				(font
					(size 1.27 1.27)
					(thickness 0.15)
				)
				(justify left bottom)
				(hide yes)
			)
		)
		(property "Footprint" "antmicro-footprints:LED_0603_1608Metric_G"
			(at 314.96 208.28 0)
			(effects
				(font
					(size 1.27 1.27)
					(thickness 0.15)
				)
				(justify left bottom)
				(hide yes)
			)
		)
		(property "Datasheet" "https://look.ams-osram.com/m/19ee86b3ae0ee95b/original/LG-L29K.pdf"
			(at 317.5 208.28 0)
			(effects
				(font
					(size 1.27 1.27)
					(thickness 0.15)
				)
				(justify left bottom)
				(hide yes)
			)
		)
		(property "Description" "LED, Green, SMD, 0603, 20 mA, 1.7 V, 570 nm"
			(at 304.8 228.6 0)
			(effects
				(font
					(size 1.27 1.27)
				)
				(hide yes)
			)
		)
		(property "MPN" "LG L29K-G2J1-24-Z"
			(at 320.04 208.28 0)
			(effects
				(font
					(size 1.27 1.27)
					(thickness 0.15)
				)
				(justify left bottom)
				(hide yes)
			)
		)
		(property "Manufacturer" "OSRAM"
			(at 322.58 208.28 0)
			(effects
				(font
					(size 1.27 1.27)
					(thickness 0.15)
				)
				(justify left bottom)
				(hide yes)
			)
		)
		(property "Color" "Green"
			(at 306.07 227.3299 90)
			(effects
				(font
					(size 1.27 1.27)
				)
				(justify right)
			)
		)
		(property "Author" "Antmicro"
			(at 325.12 208.28 0)
			(effects
				(font
					(size 1.27 1.27)
					(thickness 0.15)
				)
				(justify left bottom)
				(hide yes)
			)
		)
		(property "License" "Apache-2.0"
			(at 327.66 208.28 0)
			(effects
				(font
					(size 1.27 1.27)
					(thickness 0.15)
				)
				(justify left bottom)
				(hide yes)
			)
		)
		(pin "2"
		)
		(pin "1"
		)
		(instances
			(project "thunderbolt-to-10gbe-adapter"
				(path ""
					(reference "D11")
					(unit 1)
				)
			)
		)
	)
	(symbol
		(lib_id "antmicropower:GND")
		(at 297.18 157.48 0)
		(unit 1)
		(exclude_from_sim no)
		(in_bom yes)
		(on_board yes)
		(dnp no)
		(property "Reference" "#PWR0180"
			(at 306.07 160.02 0)
			(effects
				(font
					(size 1.27 1.27)
					(thickness 0.15)
				)
				(justify left bottom)
				(hide yes)
			)
		)
		(property "Value" "GND"
			(at 297.18 161.29 0)
			(effects
				(font
					(size 1.27 1.27)
					(thickness 0.15)
				)
			)
		)
		(property "Footprint" ""
			(at 306.07 165.1 0)
			(effects
				(font
					(size 1.27 1.27)
					(thickness 0.15)
				)
				(justify left bottom)
				(hide yes)
			)
		)
		(property "Datasheet" ""
			(at 306.07 170.18 0)
			(effects
				(font
					(size 1.27 1.27)
					(thickness 0.15)
				)
				(justify left bottom)
				(hide yes)
			)
		)
		(property "Description" ""
			(at 297.18 157.48 0)
			(effects
				(font
					(size 1.27 1.27)
				)
				(hide yes)
			)
		)
		(property "Author" "Antmicro"
			(at 306.07 165.1 0)
			(effects
				(font
					(size 1.27 1.27)
					(thickness 0.15)
				)
				(justify left bottom)
				(hide yes)
			)
		)
		(property "License" "Apache-2.0"
			(at 306.07 167.64 0)
			(effects
				(font
					(size 1.27 1.27)
					(thickness 0.15)
				)
				(justify left bottom)
				(hide yes)
			)
		)
		(pin "1"
		)
		(instances
			(project "thunderbolt-to-10gbe-adapter"
				(path ""
					(reference "#PWR0180")
					(unit 1)
				)
			)
		)
	)
	(symbol
		(lib_id "antmicropower:GND")
		(at 217.17 81.28 0)
		(unit 1)
		(exclude_from_sim no)
		(in_bom yes)
		(on_board yes)
		(dnp no)
		(property "Reference" "#PWR0152"
			(at 226.06 83.82 0)
			(effects
				(font
					(size 1.27 1.27)
					(thickness 0.15)
				)
				(justify left bottom)
				(hide yes)
			)
		)
		(property "Value" "GND"
			(at 217.17 85.09 0)
			(effects
				(font
					(size 1.27 1.27)
					(thickness 0.15)
				)
			)
		)
		(property "Footprint" ""
			(at 226.06 88.9 0)
			(effects
				(font
					(size 1.27 1.27)
					(thickness 0.15)
				)
				(justify left bottom)
				(hide yes)
			)
		)
		(property "Datasheet" ""
			(at 226.06 93.98 0)
			(effects
				(font
					(size 1.27 1.27)
					(thickness 0.15)
				)
				(justify left bottom)
				(hide yes)
			)
		)
		(property "Description" ""
			(at 217.17 81.28 0)
			(effects
				(font
					(size 1.27 1.27)
				)
				(hide yes)
			)
		)
		(property "Author" "Antmicro"
			(at 226.06 88.9 0)
			(effects
				(font
					(size 1.27 1.27)
					(thickness 0.15)
				)
				(justify left bottom)
				(hide yes)
			)
		)
		(property "License" "Apache-2.0"
			(at 226.06 91.44 0)
			(effects
				(font
					(size 1.27 1.27)
					(thickness 0.15)
				)
				(justify left bottom)
				(hide yes)
			)
		)
		(pin "1"
		)
		(instances
			(project "thunderbolt-to-10gbe-adapter"
				(path ""
					(reference "#PWR0152")
					(unit 1)
				)
			)
		)
	)
	(symbol
		(lib_id "antmicropower:GND")
		(at 247.65 195.58 0)
		(unit 1)
		(exclude_from_sim no)
		(in_bom yes)
		(on_board yes)
		(dnp no)
		(property "Reference" "#PWR0174"
			(at 256.54 198.12 0)
			(effects
				(font
					(size 1.27 1.27)
					(thickness 0.15)
				)
				(justify left bottom)
				(hide yes)
			)
		)
		(property "Value" "GND"
			(at 247.65 199.39 0)
			(effects
				(font
					(size 1.27 1.27)
					(thickness 0.15)
				)
			)
		)
		(property "Footprint" ""
			(at 256.54 203.2 0)
			(effects
				(font
					(size 1.27 1.27)
					(thickness 0.15)
				)
				(justify left bottom)
				(hide yes)
			)
		)
		(property "Datasheet" ""
			(at 256.54 208.28 0)
			(effects
				(font
					(size 1.27 1.27)
					(thickness 0.15)
				)
				(justify left bottom)
				(hide yes)
			)
		)
		(property "Description" ""
			(at 247.65 195.58 0)
			(effects
				(font
					(size 1.27 1.27)
				)
				(hide yes)
			)
		)
		(property "Author" "Antmicro"
			(at 256.54 203.2 0)
			(effects
				(font
					(size 1.27 1.27)
					(thickness 0.15)
				)
				(justify left bottom)
				(hide yes)
			)
		)
		(property "License" "Apache-2.0"
			(at 256.54 205.74 0)
			(effects
				(font
					(size 1.27 1.27)
					(thickness 0.15)
				)
				(justify left bottom)
				(hide yes)
			)
		)
		(pin "1"
		)
		(instances
			(project "thunderbolt-to-10gbe-adapter"
				(path ""
					(reference "#PWR0174")
					(unit 1)
				)
			)
		)
	)
	(symbol
		(lib_id "antmicropower:GND")
		(at 354.33 157.48 0)
		(unit 1)
		(exclude_from_sim no)
		(in_bom yes)
		(on_board yes)
		(dnp no)
		(property "Reference" "#PWR0196"
			(at 363.22 160.02 0)
			(effects
				(font
					(size 1.27 1.27)
					(thickness 0.15)
				)
				(justify left bottom)
				(hide yes)
			)
		)
		(property "Value" "GND"
			(at 354.33 161.29 0)
			(effects
				(font
					(size 1.27 1.27)
					(thickness 0.15)
				)
			)
		)
		(property "Footprint" ""
			(at 363.22 165.1 0)
			(effects
				(font
					(size 1.27 1.27)
					(thickness 0.15)
				)
				(justify left bottom)
				(hide yes)
			)
		)
		(property "Datasheet" ""
			(at 363.22 170.18 0)
			(effects
				(font
					(size 1.27 1.27)
					(thickness 0.15)
				)
				(justify left bottom)
				(hide yes)
			)
		)
		(property "Description" ""
			(at 354.33 157.48 0)
			(effects
				(font
					(size 1.27 1.27)
				)
				(hide yes)
			)
		)
		(property "Author" "Antmicro"
			(at 363.22 165.1 0)
			(effects
				(font
					(size 1.27 1.27)
					(thickness 0.15)
				)
				(justify left bottom)
				(hide yes)
			)
		)
		(property "License" "Apache-2.0"
			(at 363.22 167.64 0)
			(effects
				(font
					(size 1.27 1.27)
					(thickness 0.15)
				)
				(justify left bottom)
				(hide yes)
			)
		)
		(pin "1"
		)
		(instances
			(project "thunderbolt-to-10gbe-adapter"
				(path ""
					(reference "#PWR0196")
					(unit 1)
				)
			)
		)
	)
	(symbol
		(lib_id "antmicroResistors0402:R_330R_0402")
		(at 203.2 231.14 90)
		(unit 1)
		(exclude_from_sim no)
		(in_bom yes)
		(on_board yes)
		(dnp no)
		(property "Reference" "R84"
			(at 204.47 227.33 90)
			(effects
				(font
					(size 1.27 1.27)
					(thickness 0.15)
				)
				(justify right)
			)
		)
		(property "Value" "R_330R_0402"
			(at 215.9 210.82 0)
			(effects
				(font
					(size 1.27 1.27)
					(thickness 0.15)
				)
				(justify left bottom)
				(hide yes)
			)
		)
		(property "Footprint" "antmicro-footprints:R_0402_1005Metric"
			(at 218.44 210.82 0)
			(effects
				(font
					(size 1.27 1.27)
					(thickness 0.15)
				)
				(justify left bottom)
				(hide yes)
			)
		)
		(property "Datasheet" "https://www.bourns.com/docs/product-datasheets/cr.pdf"
			(at 220.98 210.82 0)
			(effects
				(font
					(size 1.27 1.27)
					(thickness 0.15)
				)
				(justify left bottom)
				(hide yes)
			)
		)
		(property "Description" "SMD Chip Resistor, 330 ohm, ± 1%, 62.5 mW, 0402 [1005 Metric], Thick Film, General Purpose"
			(at 233.68 210.82 0)
			(effects
				(font
					(size 1.27 1.27)
				)
				(justify left bottom)
				(hide yes)
			)
		)
		(property "MPN" "CR0402-FX-3300GLF"
			(at 223.52 210.82 0)
			(effects
				(font
					(size 1.27 1.27)
					(thickness 0.15)
				)
				(justify left bottom)
				(hide yes)
			)
		)
		(property "Manufacturer" "Bourns"
			(at 226.06 210.82 0)
			(effects
				(font
					(size 1.27 1.27)
					(thickness 0.15)
				)
				(justify left bottom)
				(hide yes)
			)
		)
		(property "License" "Apache-2.0"
			(at 228.6 210.82 0)
			(effects
				(font
					(size 1.27 1.27)
					(thickness 0.15)
				)
				(justify left bottom)
				(hide yes)
			)
		)
		(property "Author" "Antmicro"
			(at 231.14 210.82 0)
			(effects
				(font
					(size 1.27 1.27)
					(thickness 0.15)
				)
				(justify left bottom)
				(hide yes)
			)
		)
		(property "Val" "330R"
			(at 204.47 229.87 90)
			(effects
				(font
					(size 1.27 1.27)
					(thickness 0.15)
				)
				(justify right)
			)
		)
		(property "Tolerance" "1%"
			(at 213.36 210.82 0)
			(effects
				(font
					(size 1.27 1.27)
				)
				(justify left bottom)
				(hide yes)
			)
		)
		(pin "2"
		)
		(pin "1"
		)
		(instances
			(project "thunderbolt-to-10gbe-adapter"
				(path ""
					(reference "R84")
					(unit 1)
				)
			)
		)
	)
	(symbol
		(lib_id "antmicroCapacitors0402:C_1u_25V_0402")
		(at 247.65 76.2 270)
		(mirror x)
		(unit 1)
		(exclude_from_sim no)
		(in_bom yes)
		(on_board yes)
		(dnp no)
		(property "Reference" "C120"
			(at 245.872 72.39 90)
			(effects
				(font
					(size 1.27 1.27)
					(thickness 0.15)
				)
				(justify right)
			)
		)
		(property "Value" "C_1u_25V_0402"
			(at 237.49 55.88 0)
			(effects
				(font
					(size 1.27 1.27)
					(thickness 0.15)
				)
				(justify left bottom)
				(hide yes)
			)
		)
		(property "Footprint" "antmicro-footprints:C_0402_1005Metric"
			(at 234.95 55.88 0)
			(effects
				(font
					(size 1.27 1.27)
					(thickness 0.15)
				)
				(justify left bottom)
				(hide yes)
			)
		)
		(property "Datasheet" "https://www.murata.com/products/productdetail?partno=GRM155R61E105KE11%23"
			(at 232.41 55.88 0)
			(effects
				(font
					(size 1.27 1.27)
					(thickness 0.15)
				)
				(justify left bottom)
				(hide yes)
			)
		)
		(property "Description" "SMD Multilayer Ceramic Capacitor, 1 µF, 25 V, 0402 [1005 Metric], ± 10%, X5R, GRM Series"
			(at 214.63 55.88 0)
			(effects
				(font
					(size 1.27 1.27)
				)
				(justify left bottom)
				(hide yes)
			)
		)
		(property "MPN" "GRM155R61E105KE11J"
			(at 229.87 55.88 0)
			(effects
				(font
					(size 1.27 1.27)
					(thickness 0.15)
				)
				(justify left bottom)
				(hide yes)
			)
		)
		(property "Manufacturer" "Murata"
			(at 227.33 55.88 0)
			(effects
				(font
					(size 1.27 1.27)
					(thickness 0.15)
				)
				(justify left bottom)
				(hide yes)
			)
		)
		(property "License" "Apache-2.0"
			(at 224.79 55.88 0)
			(effects
				(font
					(size 1.27 1.27)
					(thickness 0.15)
				)
				(justify left bottom)
				(hide yes)
			)
		)
		(property "Author" "Antmicro"
			(at 222.25 55.88 0)
			(effects
				(font
					(size 1.27 1.27)
					(thickness 0.15)
				)
				(justify left bottom)
				(hide yes)
			)
		)
		(property "Val" "1u"
			(at 245.872 74.93 90)
			(effects
				(font
					(size 1.27 1.27)
					(thickness 0.15)
				)
				(justify right)
			)
		)
		(property "Voltage" "25V"
			(at 219.71 55.88 0)
			(effects
				(font
					(size 1.27 1.27)
				)
				(justify left bottom)
				(hide yes)
			)
		)
		(property "Dielectric" "X5R"
			(at 217.17 55.88 0)
			(effects
				(font
					(size 1.27 1.27)
				)
				(justify left bottom)
				(hide yes)
			)
		)
		(pin "2"
		)
		(pin "1"
		)
		(instances
			(project "thunderbolt-to-10gbe-adapter"
				(path ""
					(reference "C120")
					(unit 1)
				)
			)
		)
	)
	(symbol
		(lib_id "antmicroCapacitors0603:C_22u_16V_0603")
		(at 227.33 38.1 270)
		(mirror x)
		(unit 1)
		(exclude_from_sim no)
		(in_bom yes)
		(on_board yes)
		(dnp no)
		(property "Reference" "C109"
			(at 225.552 34.29 90)
			(effects
				(font
					(size 1.27 1.27)
					(thickness 0.15)
				)
				(justify right)
			)
		)
		(property "Value" "C_22u_16V_0603"
			(at 217.17 17.78 0)
			(effects
				(font
					(size 1.27 1.27)
					(thickness 0.15)
				)
				(justify left bottom)
				(hide yes)
			)
		)
		(property "Footprint" "antmicro-footprints:C_0603_1608Metric_EIA"
			(at 214.63 17.78 0)
			(effects
				(font
					(size 1.27 1.27)
					(thickness 0.15)
				)
				(justify left bottom)
				(hide yes)
			)
		)
		(property "Datasheet" "https://product.samsungsem.com/mlcc/CL10A226MO7JZN.do"
			(at 212.09 17.78 0)
			(effects
				(font
					(size 1.27 1.27)
					(thickness 0.15)
				)
				(justify left bottom)
				(hide yes)
			)
		)
		(property "Description" "SMD Multilayer Ceramic Capacitor"
			(at 227.33 38.1 0)
			(effects
				(font
					(size 1.27 1.27)
				)
				(hide yes)
			)
		)
		(property "MPN" "CL10A226MO7JZNC"
			(at 209.55 17.78 0)
			(effects
				(font
					(size 1.27 1.27)
					(thickness 0.15)
				)
				(justify left bottom)
				(hide yes)
			)
		)
		(property "Manufacturer" "Samsung Electro-Mechanics"
			(at 207.01 17.78 0)
			(effects
				(font
					(size 1.27 1.27)
					(thickness 0.15)
				)
				(justify left bottom)
				(hide yes)
			)
		)
		(property "License" "Apache-2.0"
			(at 204.47 17.78 0)
			(effects
				(font
					(size 1.27 1.27)
					(thickness 0.15)
				)
				(justify left bottom)
				(hide yes)
			)
		)
		(property "Author" "Antmicro"
			(at 201.93 17.78 0)
			(effects
				(font
					(size 1.27 1.27)
					(thickness 0.15)
				)
				(justify left bottom)
				(hide yes)
			)
		)
		(property "Val" "22u"
			(at 225.552 36.83 90)
			(effects
				(font
					(size 1.27 1.27)
					(thickness 0.15)
				)
				(justify right)
			)
		)
		(property "Voltage" "16V"
			(at 224.79 38.0935 90)
			(effects
				(font
					(size 1.27 1.27)
				)
				(justify right)
				(hide yes)
			)
		)
		(property "Dielectric" ""
			(at 196.85 17.78 0)
			(effects
				(font
					(size 1.27 1.27)
				)
				(justify left bottom)
				(hide yes)
			)
		)
		(pin "2"
		)
		(pin "1"
		)
		(instances
			(project "thunderbolt-to-10gbe-adapter"
				(path ""
					(reference "C109")
					(unit 1)
				)
			)
		)
	)
	(symbol
		(lib_id "antmicroCapacitors0402:C_1u_25V_0402")
		(at 247.65 190.5 270)
		(mirror x)
		(unit 1)
		(exclude_from_sim no)
		(in_bom yes)
		(on_board yes)
		(dnp no)
		(property "Reference" "C123"
			(at 245.872 186.69 90)
			(effects
				(font
					(size 1.27 1.27)
					(thickness 0.15)
				)
				(justify right)
			)
		)
		(property "Value" "C_1u_25V_0402"
			(at 237.49 170.18 0)
			(effects
				(font
					(size 1.27 1.27)
					(thickness 0.15)
				)
				(justify left bottom)
				(hide yes)
			)
		)
		(property "Footprint" "antmicro-footprints:C_0402_1005Metric"
			(at 234.95 170.18 0)
			(effects
				(font
					(size 1.27 1.27)
					(thickness 0.15)
				)
				(justify left bottom)
				(hide yes)
			)
		)
		(property "Datasheet" "https://www.murata.com/products/productdetail?partno=GRM155R61E105KE11%23"
			(at 232.41 170.18 0)
			(effects
				(font
					(size 1.27 1.27)
					(thickness 0.15)
				)
				(justify left bottom)
				(hide yes)
			)
		)
		(property "Description" "SMD Multilayer Ceramic Capacitor, 1 µF, 25 V, 0402 [1005 Metric], ± 10%, X5R, GRM Series"
			(at 214.63 170.18 0)
			(effects
				(font
					(size 1.27 1.27)
				)
				(justify left bottom)
				(hide yes)
			)
		)
		(property "MPN" "GRM155R61E105KE11J"
			(at 229.87 170.18 0)
			(effects
				(font
					(size 1.27 1.27)
					(thickness 0.15)
				)
				(justify left bottom)
				(hide yes)
			)
		)
		(property "Manufacturer" "Murata"
			(at 227.33 170.18 0)
			(effects
				(font
					(size 1.27 1.27)
					(thickness 0.15)
				)
				(justify left bottom)
				(hide yes)
			)
		)
		(property "License" "Apache-2.0"
			(at 224.79 170.18 0)
			(effects
				(font
					(size 1.27 1.27)
					(thickness 0.15)
				)
				(justify left bottom)
				(hide yes)
			)
		)
		(property "Author" "Antmicro"
			(at 222.25 170.18 0)
			(effects
				(font
					(size 1.27 1.27)
					(thickness 0.15)
				)
				(justify left bottom)
				(hide yes)
			)
		)
		(property "Val" "1u"
			(at 245.872 189.23 90)
			(effects
				(font
					(size 1.27 1.27)
					(thickness 0.15)
				)
				(justify right)
			)
		)
		(property "Voltage" "25V"
			(at 219.71 170.18 0)
			(effects
				(font
					(size 1.27 1.27)
				)
				(justify left bottom)
				(hide yes)
			)
		)
		(property "Dielectric" "X5R"
			(at 217.17 170.18 0)
			(effects
				(font
					(size 1.27 1.27)
				)
				(justify left bottom)
				(hide yes)
			)
		)
		(pin "2"
		)
		(pin "1"
		)
		(instances
			(project "thunderbolt-to-10gbe-adapter"
				(path ""
					(reference "C123")
					(unit 1)
				)
			)
		)
	)
	(symbol
		(lib_id "antmicropower:GND")
		(at 374.65 81.28 0)
		(unit 1)
		(exclude_from_sim no)
		(in_bom yes)
		(on_board yes)
		(dnp no)
		(property "Reference" "#PWR0204"
			(at 383.54 83.82 0)
			(effects
				(font
					(size 1.27 1.27)
					(thickness 0.15)
				)
				(justify left bottom)
				(hide yes)
			)
		)
		(property "Value" "GND"
			(at 374.65 85.09 0)
			(effects
				(font
					(size 1.27 1.27)
					(thickness 0.15)
				)
			)
		)
		(property "Footprint" ""
			(at 383.54 88.9 0)
			(effects
				(font
					(size 1.27 1.27)
					(thickness 0.15)
				)
				(justify left bottom)
				(hide yes)
			)
		)
		(property "Datasheet" ""
			(at 383.54 93.98 0)
			(effects
				(font
					(size 1.27 1.27)
					(thickness 0.15)
				)
				(justify left bottom)
				(hide yes)
			)
		)
		(property "Description" ""
			(at 374.65 81.28 0)
			(effects
				(font
					(size 1.27 1.27)
				)
				(hide yes)
			)
		)
		(property "Author" "Antmicro"
			(at 383.54 88.9 0)
			(effects
				(font
					(size 1.27 1.27)
					(thickness 0.15)
				)
				(justify left bottom)
				(hide yes)
			)
		)
		(property "License" "Apache-2.0"
			(at 383.54 91.44 0)
			(effects
				(font
					(size 1.27 1.27)
					(thickness 0.15)
				)
				(justify left bottom)
				(hide yes)
			)
		)
		(pin "1"
		)
		(instances
			(project "thunderbolt-to-10gbe-adapter"
				(path ""
					(reference "#PWR0204")
					(unit 1)
				)
			)
		)
	)
	(symbol
		(lib_id "antmicropower:GND")
		(at 297.18 81.28 0)
		(unit 1)
		(exclude_from_sim no)
		(in_bom yes)
		(on_board yes)
		(dnp no)
		(property "Reference" "#PWR0178"
			(at 306.07 83.82 0)
			(effects
				(font
					(size 1.27 1.27)
					(thickness 0.15)
				)
				(justify left bottom)
				(hide yes)
			)
		)
		(property "Value" "GND"
			(at 297.18 85.09 0)
			(effects
				(font
					(size 1.27 1.27)
					(thickness 0.15)
				)
			)
		)
		(property "Footprint" ""
			(at 306.07 88.9 0)
			(effects
				(font
					(size 1.27 1.27)
					(thickness 0.15)
				)
				(justify left bottom)
				(hide yes)
			)
		)
		(property "Datasheet" ""
			(at 306.07 93.98 0)
			(effects
				(font
					(size 1.27 1.27)
					(thickness 0.15)
				)
				(justify left bottom)
				(hide yes)
			)
		)
		(property "Description" ""
			(at 297.18 81.28 0)
			(effects
				(font
					(size 1.27 1.27)
				)
				(hide yes)
			)
		)
		(property "Author" "Antmicro"
			(at 306.07 88.9 0)
			(effects
				(font
					(size 1.27 1.27)
					(thickness 0.15)
				)
				(justify left bottom)
				(hide yes)
			)
		)
		(property "License" "Apache-2.0"
			(at 306.07 91.44 0)
			(effects
				(font
					(size 1.27 1.27)
					(thickness 0.15)
				)
				(justify left bottom)
				(hide yes)
			)
		)
		(pin "1"
		)
		(instances
			(project "thunderbolt-to-10gbe-adapter"
				(path ""
					(reference "#PWR0178")
					(unit 1)
				)
			)
		)
	)
	(symbol
		(lib_id "antmicropower:GND")
		(at 227.33 157.48 0)
		(unit 1)
		(exclude_from_sim no)
		(in_bom yes)
		(on_board yes)
		(dnp no)
		(property "Reference" "#PWR0162"
			(at 236.22 160.02 0)
			(effects
				(font
					(size 1.27 1.27)
					(thickness 0.15)
				)
				(justify left bottom)
				(hide yes)
			)
		)
		(property "Value" "GND"
			(at 227.33 161.29 0)
			(effects
				(font
					(size 1.27 1.27)
					(thickness 0.15)
				)
			)
		)
		(property "Footprint" ""
			(at 236.22 165.1 0)
			(effects
				(font
					(size 1.27 1.27)
					(thickness 0.15)
				)
				(justify left bottom)
				(hide yes)
			)
		)
		(property "Datasheet" ""
			(at 236.22 170.18 0)
			(effects
				(font
					(size 1.27 1.27)
					(thickness 0.15)
				)
				(justify left bottom)
				(hide yes)
			)
		)
		(property "Description" ""
			(at 227.33 157.48 0)
			(effects
				(font
					(size 1.27 1.27)
				)
				(hide yes)
			)
		)
		(property "Author" "Antmicro"
			(at 236.22 165.1 0)
			(effects
				(font
					(size 1.27 1.27)
					(thickness 0.15)
				)
				(justify left bottom)
				(hide yes)
			)
		)
		(property "License" "Apache-2.0"
			(at 236.22 167.64 0)
			(effects
				(font
					(size 1.27 1.27)
					(thickness 0.15)
				)
				(justify left bottom)
				(hide yes)
			)
		)
		(pin "1"
		)
		(instances
			(project "thunderbolt-to-10gbe-adapter"
				(path ""
					(reference "#PWR0162")
					(unit 1)
				)
			)
		)
	)
	(symbol
		(lib_id "antmicropower:GND")
		(at 203.2 246.38 0)
		(mirror y)
		(unit 1)
		(exclude_from_sim no)
		(in_bom yes)
		(on_board yes)
		(dnp no)
		(property "Reference" "#PWR0149"
			(at 194.31 248.92 0)
			(effects
				(font
					(size 1.27 1.27)
					(thickness 0.15)
				)
				(justify left bottom)
				(hide yes)
			)
		)
		(property "Value" "GND"
			(at 203.2 250.19 0)
			(effects
				(font
					(size 1.27 1.27)
					(thickness 0.15)
				)
			)
		)
		(property "Footprint" ""
			(at 194.31 254 0)
			(effects
				(font
					(size 1.27 1.27)
					(thickness 0.15)
				)
				(justify left bottom)
				(hide yes)
			)
		)
		(property "Datasheet" ""
			(at 194.31 259.08 0)
			(effects
				(font
					(size 1.27 1.27)
					(thickness 0.15)
				)
				(justify left bottom)
				(hide yes)
			)
		)
		(property "Description" ""
			(at 203.2 246.38 0)
			(effects
				(font
					(size 1.27 1.27)
				)
				(hide yes)
			)
		)
		(property "Author" "Antmicro"
			(at 194.31 254 0)
			(effects
				(font
					(size 1.27 1.27)
					(thickness 0.15)
				)
				(justify left bottom)
				(hide yes)
			)
		)
		(property "License" "Apache-2.0"
			(at 194.31 256.54 0)
			(effects
				(font
					(size 1.27 1.27)
					(thickness 0.15)
				)
				(justify left bottom)
				(hide yes)
			)
		)
		(pin "1"
		)
		(instances
			(project "thunderbolt-to-10gbe-adapter"
				(path ""
					(reference "#PWR0149")
					(unit 1)
				)
			)
		)
	)
	(symbol
		(lib_id "antmicropower:GND")
		(at 227.33 81.28 0)
		(unit 1)
		(exclude_from_sim no)
		(in_bom yes)
		(on_board yes)
		(dnp no)
		(property "Reference" "#PWR0160"
			(at 236.22 83.82 0)
			(effects
				(font
					(size 1.27 1.27)
					(thickness 0.15)
				)
				(justify left bottom)
				(hide yes)
			)
		)
		(property "Value" "GND"
			(at 227.33 85.09 0)
			(effects
				(font
					(size 1.27 1.27)
					(thickness 0.15)
				)
			)
		)
		(property "Footprint" ""
			(at 236.22 88.9 0)
			(effects
				(font
					(size 1.27 1.27)
					(thickness 0.15)
				)
				(justify left bottom)
				(hide yes)
			)
		)
		(property "Datasheet" ""
			(at 236.22 93.98 0)
			(effects
				(font
					(size 1.27 1.27)
					(thickness 0.15)
				)
				(justify left bottom)
				(hide yes)
			)
		)
		(property "Description" ""
			(at 227.33 81.28 0)
			(effects
				(font
					(size 1.27 1.27)
				)
				(hide yes)
			)
		)
		(property "Author" "Antmicro"
			(at 236.22 88.9 0)
			(effects
				(font
					(size 1.27 1.27)
					(thickness 0.15)
				)
				(justify left bottom)
				(hide yes)
			)
		)
		(property "License" "Apache-2.0"
			(at 236.22 91.44 0)
			(effects
				(font
					(size 1.27 1.27)
					(thickness 0.15)
				)
				(justify left bottom)
				(hide yes)
			)
		)
		(pin "1"
		)
		(instances
			(project "thunderbolt-to-10gbe-adapter"
				(path ""
					(reference "#PWR0160")
					(unit 1)
				)
			)
		)
	)
	(symbol
		(lib_id "antmicroCapacitors0402:C_100n_0402")
		(at 237.49 152.4 270)
		(mirror x)
		(unit 1)
		(exclude_from_sim no)
		(in_bom yes)
		(on_board yes)
		(dnp no)
		(property "Reference" "C117"
			(at 235.712 148.59 90)
			(effects
				(font
					(size 1.27 1.27)
					(thickness 0.15)
				)
				(justify right)
			)
		)
		(property "Value" "C_100n_0402"
			(at 227.33 132.08 0)
			(effects
				(font
					(size 1.27 1.27)
					(thickness 0.15)
				)
				(justify left bottom)
				(hide yes)
			)
		)
		(property "Footprint" "antmicro-footprints:C_0402_1005Metric"
			(at 224.79 132.08 0)
			(effects
				(font
					(size 1.27 1.27)
					(thickness 0.15)
				)
				(justify left bottom)
				(hide yes)
			)
		)
		(property "Datasheet" "https://www.murata.com/products/productdetail?partno=GRM155R61H104KE14%23"
			(at 222.25 132.08 0)
			(effects
				(font
					(size 1.27 1.27)
					(thickness 0.15)
				)
				(justify left bottom)
				(hide yes)
			)
		)
		(property "Description" "SMD Multilayer Ceramic Capacitor, 0.1 µF, 50 V, 0402 [1005 Metric], ± 10%, X5R, GRM Series"
			(at 204.47 132.08 0)
			(effects
				(font
					(size 1.27 1.27)
				)
				(justify left bottom)
				(hide yes)
			)
		)
		(property "MPN" "GRM155R61H104KE14D"
			(at 219.71 132.08 0)
			(effects
				(font
					(size 1.27 1.27)
					(thickness 0.15)
				)
				(justify left bottom)
				(hide yes)
			)
		)
		(property "Manufacturer" "Murata"
			(at 217.17 132.08 0)
			(effects
				(font
					(size 1.27 1.27)
					(thickness 0.15)
				)
				(justify left bottom)
				(hide yes)
			)
		)
		(property "License" "Apache-2.0"
			(at 214.63 132.08 0)
			(effects
				(font
					(size 1.27 1.27)
					(thickness 0.15)
				)
				(justify left bottom)
				(hide yes)
			)
		)
		(property "Author" "Antmicro"
			(at 212.09 132.08 0)
			(effects
				(font
					(size 1.27 1.27)
					(thickness 0.15)
				)
				(justify left bottom)
				(hide yes)
			)
		)
		(property "Val" "100n"
			(at 235.712 151.13 90)
			(effects
				(font
					(size 1.27 1.27)
					(thickness 0.15)
				)
				(justify right)
			)
		)
		(property "Voltage" "50V"
			(at 209.55 132.08 0)
			(effects
				(font
					(size 1.27 1.27)
				)
				(justify left bottom)
				(hide yes)
			)
		)
		(property "Dielectric" "X5R"
			(at 207.01 132.08 0)
			(effects
				(font
					(size 1.27 1.27)
				)
				(justify left bottom)
				(hide yes)
			)
		)
		(pin "1"
		)
		(pin "2"
		)
		(instances
			(project "thunderbolt-to-10gbe-adapter"
				(path ""
					(reference "C117")
					(unit 1)
				)
			)
		)
	)
	(symbol
		(lib_id "antmicroCapacitors0603:C_22u_16V_0603")
		(at 364.49 152.4 90)
		(unit 1)
		(exclude_from_sim no)
		(in_bom yes)
		(on_board yes)
		(dnp no)
		(property "Reference" "C147"
			(at 366.268 148.59 90)
			(effects
				(font
					(size 1.27 1.27)
					(thickness 0.15)
				)
				(justify right)
			)
		)
		(property "Value" "C_22u_16V_0603"
			(at 374.65 132.08 0)
			(effects
				(font
					(size 1.27 1.27)
					(thickness 0.15)
				)
				(justify left bottom)
				(hide yes)
			)
		)
		(property "Footprint" "antmicro-footprints:C_0603_1608Metric_EIA"
			(at 377.19 132.08 0)
			(effects
				(font
					(size 1.27 1.27)
					(thickness 0.15)
				)
				(justify left bottom)
				(hide yes)
			)
		)
		(property "Datasheet" "https://product.samsungsem.com/mlcc/CL10A226MO7JZN.do"
			(at 379.73 132.08 0)
			(effects
				(font
					(size 1.27 1.27)
					(thickness 0.15)
				)
				(justify left bottom)
				(hide yes)
			)
		)
		(property "Description" "SMD Multilayer Ceramic Capacitor"
			(at 364.49 152.4 0)
			(effects
				(font
					(size 1.27 1.27)
				)
				(hide yes)
			)
		)
		(property "MPN" "CL10A226MO7JZNC"
			(at 382.27 132.08 0)
			(effects
				(font
					(size 1.27 1.27)
					(thickness 0.15)
				)
				(justify left bottom)
				(hide yes)
			)
		)
		(property "Manufacturer" "Samsung Electro-Mechanics"
			(at 384.81 132.08 0)
			(effects
				(font
					(size 1.27 1.27)
					(thickness 0.15)
				)
				(justify left bottom)
				(hide yes)
			)
		)
		(property "License" "Apache-2.0"
			(at 387.35 132.08 0)
			(effects
				(font
					(size 1.27 1.27)
					(thickness 0.15)
				)
				(justify left bottom)
				(hide yes)
			)
		)
		(property "Author" "Antmicro"
			(at 389.89 132.08 0)
			(effects
				(font
					(size 1.27 1.27)
					(thickness 0.15)
				)
				(justify left bottom)
				(hide yes)
			)
		)
		(property "Val" "22u"
			(at 366.268 151.13 90)
			(effects
				(font
					(size 1.27 1.27)
					(thickness 0.15)
				)
				(justify right)
			)
		)
		(property "Voltage" "16V"
			(at 367.03 152.3935 90)
			(effects
				(font
					(size 1.27 1.27)
				)
				(justify right)
				(hide yes)
			)
		)
		(property "Dielectric" ""
			(at 394.97 132.08 0)
			(effects
				(font
					(size 1.27 1.27)
				)
				(justify left bottom)
				(hide yes)
			)
		)
		(pin "2"
		)
		(pin "1"
		)
		(instances
			(project "thunderbolt-to-10gbe-adapter"
				(path ""
					(reference "C147")
					(unit 1)
				)
			)
		)
	)
	(symbol
		(lib_id "antmicroResistors0402:R_20k_0402")
		(at 332.74 185.42 90)
		(unit 1)
		(exclude_from_sim no)
		(in_bom yes)
		(on_board yes)
		(dnp no)
		(property "Reference" "R106"
			(at 334.01 181.61 90)
			(effects
				(font
					(size 1.27 1.27)
					(thickness 0.15)
				)
				(justify right)
			)
		)
		(property "Value" "R_20k_0402"
			(at 345.44 165.1 0)
			(effects
				(font
					(size 1.27 1.27)
					(thickness 0.15)
				)
				(justify left bottom)
				(hide yes)
			)
		)
		(property "Footprint" "antmicro-footprints:R_0402_1005Metric"
			(at 347.98 165.1 0)
			(effects
				(font
					(size 1.27 1.27)
					(thickness 0.15)
				)
				(justify left bottom)
				(hide yes)
			)
		)
		(property "Datasheet" "https://www.bourns.com/docs/product-datasheets/cr.pdf"
			(at 350.52 165.1 0)
			(effects
				(font
					(size 1.27 1.27)
					(thickness 0.15)
				)
				(justify left bottom)
				(hide yes)
			)
		)
		(property "Description" "SMD Chip Resistor, 20 kohm, ± 1%, 62.5 mW, 0402 [1005 Metric], Thick Film, General Purpose"
			(at 363.22 165.1 0)
			(effects
				(font
					(size 1.27 1.27)
				)
				(justify left bottom)
				(hide yes)
			)
		)
		(property "MPN" "CR0402-FX-2002GLF"
			(at 353.06 165.1 0)
			(effects
				(font
					(size 1.27 1.27)
					(thickness 0.15)
				)
				(justify left bottom)
				(hide yes)
			)
		)
		(property "Manufacturer" "Bourns"
			(at 355.6 165.1 0)
			(effects
				(font
					(size 1.27 1.27)
					(thickness 0.15)
				)
				(justify left bottom)
				(hide yes)
			)
		)
		(property "License" "Apache-2.0"
			(at 358.14 165.1 0)
			(effects
				(font
					(size 1.27 1.27)
					(thickness 0.15)
				)
				(justify left bottom)
				(hide yes)
			)
		)
		(property "Author" "Antmicro"
			(at 360.68 165.1 0)
			(effects
				(font
					(size 1.27 1.27)
					(thickness 0.15)
				)
				(justify left bottom)
				(hide yes)
			)
		)
		(property "Val" "20k"
			(at 334.01 184.15 90)
			(effects
				(font
					(size 1.27 1.27)
					(thickness 0.15)
				)
				(justify right)
			)
		)
		(property "Tolerance" "1%"
			(at 342.9 165.1 0)
			(effects
				(font
					(size 1.27 1.27)
				)
				(justify left bottom)
				(hide yes)
			)
		)
		(pin "2"
		)
		(pin "1"
		)
		(instances
			(project "thunderbolt-to-10gbe-adapter"
				(path ""
					(reference "R106")
					(unit 1)
				)
			)
		)
	)
	(symbol
		(lib_id "antmicropower:GND")
		(at 217.17 119.38 0)
		(unit 1)
		(exclude_from_sim no)
		(in_bom yes)
		(on_board yes)
		(dnp no)
		(property "Reference" "#PWR0154"
			(at 226.06 121.92 0)
			(effects
				(font
					(size 1.27 1.27)
					(thickness 0.15)
				)
				(justify left bottom)
				(hide yes)
			)
		)
		(property "Value" "GND"
			(at 217.17 123.19 0)
			(effects
				(font
					(size 1.27 1.27)
					(thickness 0.15)
				)
			)
		)
		(property "Footprint" ""
			(at 226.06 127 0)
			(effects
				(font
					(size 1.27 1.27)
					(thickness 0.15)
				)
				(justify left bottom)
				(hide yes)
			)
		)
		(property "Datasheet" ""
			(at 226.06 132.08 0)
			(effects
				(font
					(size 1.27 1.27)
					(thickness 0.15)
				)
				(justify left bottom)
				(hide yes)
			)
		)
		(property "Description" ""
			(at 217.17 119.38 0)
			(effects
				(font
					(size 1.27 1.27)
				)
				(hide yes)
			)
		)
		(property "Author" "Antmicro"
			(at 226.06 127 0)
			(effects
				(font
					(size 1.27 1.27)
					(thickness 0.15)
				)
				(justify left bottom)
				(hide yes)
			)
		)
		(property "License" "Apache-2.0"
			(at 226.06 129.54 0)
			(effects
				(font
					(size 1.27 1.27)
					(thickness 0.15)
				)
				(justify left bottom)
				(hide yes)
			)
		)
		(pin "1"
		)
		(instances
			(project "thunderbolt-to-10gbe-adapter"
				(path ""
					(reference "#PWR0154")
					(unit 1)
				)
			)
		)
	)
	(symbol
		(lib_id "antmicroResistors0402:R_20k_0402")
		(at 332.74 147.32 90)
		(unit 1)
		(exclude_from_sim no)
		(in_bom yes)
		(on_board yes)
		(dnp no)
		(property "Reference" "R104"
			(at 334.01 143.51 90)
			(effects
				(font
					(size 1.27 1.27)
					(thickness 0.15)
				)
				(justify right)
			)
		)
		(property "Value" "R_20k_0402"
			(at 345.44 127 0)
			(effects
				(font
					(size 1.27 1.27)
					(thickness 0.15)
				)
				(justify left bottom)
				(hide yes)
			)
		)
		(property "Footprint" "antmicro-footprints:R_0402_1005Metric"
			(at 347.98 127 0)
			(effects
				(font
					(size 1.27 1.27)
					(thickness 0.15)
				)
				(justify left bottom)
				(hide yes)
			)
		)
		(property "Datasheet" "https://www.bourns.com/docs/product-datasheets/cr.pdf"
			(at 350.52 127 0)
			(effects
				(font
					(size 1.27 1.27)
					(thickness 0.15)
				)
				(justify left bottom)
				(hide yes)
			)
		)
		(property "Description" "SMD Chip Resistor, 20 kohm, ± 1%, 62.5 mW, 0402 [1005 Metric], Thick Film, General Purpose"
			(at 363.22 127 0)
			(effects
				(font
					(size 1.27 1.27)
				)
				(justify left bottom)
				(hide yes)
			)
		)
		(property "MPN" "CR0402-FX-2002GLF"
			(at 353.06 127 0)
			(effects
				(font
					(size 1.27 1.27)
					(thickness 0.15)
				)
				(justify left bottom)
				(hide yes)
			)
		)
		(property "Manufacturer" "Bourns"
			(at 355.6 127 0)
			(effects
				(font
					(size 1.27 1.27)
					(thickness 0.15)
				)
				(justify left bottom)
				(hide yes)
			)
		)
		(property "License" "Apache-2.0"
			(at 358.14 127 0)
			(effects
				(font
					(size 1.27 1.27)
					(thickness 0.15)
				)
				(justify left bottom)
				(hide yes)
			)
		)
		(property "Author" "Antmicro"
			(at 360.68 127 0)
			(effects
				(font
					(size 1.27 1.27)
					(thickness 0.15)
				)
				(justify left bottom)
				(hide yes)
			)
		)
		(property "Val" "20k"
			(at 334.01 146.05 90)
			(effects
				(font
					(size 1.27 1.27)
					(thickness 0.15)
				)
				(justify right)
			)
		)
		(property "Tolerance" "1%"
			(at 342.9 127 0)
			(effects
				(font
					(size 1.27 1.27)
				)
				(justify left bottom)
				(hide yes)
			)
		)
		(pin "2"
		)
		(pin "1"
		)
		(instances
			(project "thunderbolt-to-10gbe-adapter"
				(path ""
					(reference "R104")
					(unit 1)
				)
			)
		)
	)
	(symbol
		(lib_id "antmicropower:GND")
		(at 374.65 43.18 0)
		(unit 1)
		(exclude_from_sim no)
		(in_bom yes)
		(on_board yes)
		(dnp no)
		(property "Reference" "#PWR0203"
			(at 383.54 45.72 0)
			(effects
				(font
					(size 1.27 1.27)
					(thickness 0.15)
				)
				(justify left bottom)
				(hide yes)
			)
		)
		(property "Value" "GND"
			(at 374.65 46.99 0)
			(effects
				(font
					(size 1.27 1.27)
					(thickness 0.15)
				)
			)
		)
		(property "Footprint" ""
			(at 383.54 50.8 0)
			(effects
				(font
					(size 1.27 1.27)
					(thickness 0.15)
				)
				(justify left bottom)
				(hide yes)
			)
		)
		(property "Datasheet" ""
			(at 383.54 55.88 0)
			(effects
				(font
					(size 1.27 1.27)
					(thickness 0.15)
				)
				(justify left bottom)
				(hide yes)
			)
		)
		(property "Description" ""
			(at 374.65 43.18 0)
			(effects
				(font
					(size 1.27 1.27)
				)
				(hide yes)
			)
		)
		(property "Author" "Antmicro"
			(at 383.54 50.8 0)
			(effects
				(font
					(size 1.27 1.27)
					(thickness 0.15)
				)
				(justify left bottom)
				(hide yes)
			)
		)
		(property "License" "Apache-2.0"
			(at 383.54 53.34 0)
			(effects
				(font
					(size 1.27 1.27)
					(thickness 0.15)
				)
				(justify left bottom)
				(hide yes)
			)
		)
		(pin "1"
		)
		(instances
			(project "thunderbolt-to-10gbe-adapter"
				(path ""
					(reference "#PWR0203")
					(unit 1)
				)
			)
		)
	)
	(symbol
		(lib_id "antmicroDCDCConverters:TPS566231P")
		(at 276.86 139.7 0)
		(unit 1)
		(exclude_from_sim no)
		(in_bom yes)
		(on_board yes)
		(dnp no)
		(fields_autoplaced yes)
		(property "Reference" "U12"
			(at 285.75 133.35 0)
			(effects
				(font
					(size 1.27 1.27)
					(thickness 0.15)
				)
			)
		)
		(property "Value" "TPS566231P"
			(at 309.88 144.78 0)
			(effects
				(font
					(size 1.27 1.27)
					(thickness 0.15)
				)
				(justify left bottom)
				(hide yes)
			)
		)
		(property "Footprint" "antmicro-footprints:VQFN-HR-9_2x1.5mm"
			(at 309.88 147.32 0)
			(effects
				(font
					(size 1.27 1.27)
					(thickness 0.15)
				)
				(justify left bottom)
				(hide yes)
			)
		)
		(property "Datasheet" "https://www.ti.com/lit/ds/symlink/tps566231.pdf"
			(at 309.88 149.86 0)
			(effects
				(font
					(size 1.27 1.27)
					(thickness 0.15)
				)
				(justify left bottom)
				(hide yes)
			)
		)
		(property "Description" "Switching Voltage Regulators 3-V to 18-V, 6-A synchronous buck converter"
			(at 309.88 162.56 0)
			(effects
				(font
					(size 1.27 1.27)
				)
				(justify left bottom)
				(hide yes)
			)
		)
		(property "Manufacturer" "Texas Instruments"
			(at 309.88 152.4 0)
			(effects
				(font
					(size 1.27 1.27)
					(thickness 0.15)
				)
				(justify left bottom)
				(hide yes)
			)
		)
		(property "MPN" "TPS566231PRQFR"
			(at 285.75 135.89 0)
			(effects
				(font
					(size 1.27 1.27)
					(thickness 0.15)
				)
			)
		)
		(property "Author" "Antmicro"
			(at 309.88 157.48 0)
			(effects
				(font
					(size 1.27 1.27)
					(thickness 0.15)
				)
				(justify left bottom)
				(hide yes)
			)
		)
		(property "License" "Apache-2.0"
			(at 309.88 160.02 0)
			(effects
				(font
					(size 1.27 1.27)
					(thickness 0.15)
				)
				(justify left bottom)
				(hide yes)
			)
		)
		(pin "1"
		)
		(pin "2"
		)
		(pin "3"
		)
		(pin "9"
		)
		(pin "5"
		)
		(pin "6"
		)
		(pin "8"
		)
		(pin "4"
		)
		(pin "7"
		)
		(instances
			(project "thunderbolt-to-10gbe-adapter"
				(path ""
					(reference "U12")
					(unit 1)
				)
			)
		)
	)
	(symbol
		(lib_id "antmicroTestPoints:TP_0.75mm_SMD")
		(at 391.16 228.6 0)
		(unit 1)
		(exclude_from_sim no)
		(in_bom no)
		(on_board yes)
		(dnp no)
		(fields_autoplaced yes)
		(property "Reference" "TP15"
			(at 396.24 228.6 0)
			(effects
				(font
					(size 1.27 1.27)
					(thickness 0.15)
				)
				(justify left)
			)
		)
		(property "Value" "TP_0.75mm_SMD"
			(at 401.32 232.41 0)
			(effects
				(font
					(size 1.27 1.27)
					(thickness 0.15)
				)
				(justify left bottom)
				(hide yes)
			)
		)
		(property "Footprint" "antmicro-footprints:TP_SMD_0.75mm"
			(at 401.32 234.95 0)
			(effects
				(font
					(size 1.27 1.27)
					(thickness 0.15)
				)
				(justify left bottom)
				(hide yes)
			)
		)
		(property "Datasheet" ""
			(at 408.94 241.3 0)
			(effects
				(font
					(size 1.27 1.27)
					(thickness 0.15)
				)
				(justify left bottom)
				(hide yes)
			)
		)
		(property "Description" "SMT test point"
			(at 401.955 242.57 0)
			(effects
				(font
					(size 1.27 1.27)
				)
				(justify left bottom)
				(hide yes)
			)
		)
		(property "MPN" ""
			(at 401.955 240.03 0)
			(effects
				(font
					(size 1.27 1.27)
					(thickness 0.15)
				)
				(justify left bottom)
				(hide yes)
			)
		)
		(property "Manufacturer" ""
			(at 401.955 234.95 0)
			(effects
				(font
					(size 1.27 1.27)
					(thickness 0.15)
				)
				(justify left bottom)
				(hide yes)
			)
		)
		(property "Author" "Antmicro"
			(at 401.32 237.49 0)
			(effects
				(font
					(size 1.27 1.27)
					(thickness 0.15)
				)
				(justify left bottom)
				(hide yes)
			)
		)
		(property "License" "Apache-2.0"
			(at 401.32 240.03 0)
			(effects
				(font
					(size 1.27 1.27)
					(thickness 0.15)
				)
				(justify left bottom)
				(hide yes)
			)
		)
		(pin "1"
		)
		(instances
			(project "thunderbolt-to-10gbe-adapter"
				(path ""
					(reference "TP15")
					(unit 1)
				)
			)
		)
	)
	(symbol
		(lib_id "antmicropower:GND")
		(at 237.49 119.38 0)
		(unit 1)
		(exclude_from_sim no)
		(in_bom yes)
		(on_board yes)
		(dnp no)
		(property "Reference" "#PWR0167"
			(at 246.38 121.92 0)
			(effects
				(font
					(size 1.27 1.27)
					(thickness 0.15)
				)
				(justify left bottom)
				(hide yes)
			)
		)
		(property "Value" "GND"
			(at 237.49 123.19 0)
			(effects
				(font
					(size 1.27 1.27)
					(thickness 0.15)
				)
			)
		)
		(property "Footprint" ""
			(at 246.38 127 0)
			(effects
				(font
					(size 1.27 1.27)
					(thickness 0.15)
				)
				(justify left bottom)
				(hide yes)
			)
		)
		(property "Datasheet" ""
			(at 246.38 132.08 0)
			(effects
				(font
					(size 1.27 1.27)
					(thickness 0.15)
				)
				(justify left bottom)
				(hide yes)
			)
		)
		(property "Description" ""
			(at 237.49 119.38 0)
			(effects
				(font
					(size 1.27 1.27)
				)
				(hide yes)
			)
		)
		(property "Author" "Antmicro"
			(at 246.38 127 0)
			(effects
				(font
					(size 1.27 1.27)
					(thickness 0.15)
				)
				(justify left bottom)
				(hide yes)
			)
		)
		(property "License" "Apache-2.0"
			(at 246.38 129.54 0)
			(effects
				(font
					(size 1.27 1.27)
					(thickness 0.15)
				)
				(justify left bottom)
				(hide yes)
			)
		)
		(pin "1"
		)
		(instances
			(project "thunderbolt-to-10gbe-adapter"
				(path ""
					(reference "#PWR0167")
					(unit 1)
				)
			)
		)
	)
	(symbol
		(lib_id "antmicroCapacitors0402:C_1u_25V_0402")
		(at 247.65 114.3 270)
		(mirror x)
		(unit 1)
		(exclude_from_sim no)
		(in_bom yes)
		(on_board yes)
		(dnp no)
		(property "Reference" "C121"
			(at 245.872 110.49 90)
			(effects
				(font
					(size 1.27 1.27)
					(thickness 0.15)
				)
				(justify right)
			)
		)
		(property "Value" "C_1u_25V_0402"
			(at 237.49 93.98 0)
			(effects
				(font
					(size 1.27 1.27)
					(thickness 0.15)
				)
				(justify left bottom)
				(hide yes)
			)
		)
		(property "Footprint" "antmicro-footprints:C_0402_1005Metric"
			(at 234.95 93.98 0)
			(effects
				(font
					(size 1.27 1.27)
					(thickness 0.15)
				)
				(justify left bottom)
				(hide yes)
			)
		)
		(property "Datasheet" "https://www.murata.com/products/productdetail?partno=GRM155R61E105KE11%23"
			(at 232.41 93.98 0)
			(effects
				(font
					(size 1.27 1.27)
					(thickness 0.15)
				)
				(justify left bottom)
				(hide yes)
			)
		)
		(property "Description" "SMD Multilayer Ceramic Capacitor, 1 µF, 25 V, 0402 [1005 Metric], ± 10%, X5R, GRM Series"
			(at 214.63 93.98 0)
			(effects
				(font
					(size 1.27 1.27)
				)
				(justify left bottom)
				(hide yes)
			)
		)
		(property "MPN" "GRM155R61E105KE11J"
			(at 229.87 93.98 0)
			(effects
				(font
					(size 1.27 1.27)
					(thickness 0.15)
				)
				(justify left bottom)
				(hide yes)
			)
		)
		(property "Manufacturer" "Murata"
			(at 227.33 93.98 0)
			(effects
				(font
					(size 1.27 1.27)
					(thickness 0.15)
				)
				(justify left bottom)
				(hide yes)
			)
		)
		(property "License" "Apache-2.0"
			(at 224.79 93.98 0)
			(effects
				(font
					(size 1.27 1.27)
					(thickness 0.15)
				)
				(justify left bottom)
				(hide yes)
			)
		)
		(property "Author" "Antmicro"
			(at 222.25 93.98 0)
			(effects
				(font
					(size 1.27 1.27)
					(thickness 0.15)
				)
				(justify left bottom)
				(hide yes)
			)
		)
		(property "Val" "1u"
			(at 245.872 113.03 90)
			(effects
				(font
					(size 1.27 1.27)
					(thickness 0.15)
				)
				(justify right)
			)
		)
		(property "Voltage" "25V"
			(at 219.71 93.98 0)
			(effects
				(font
					(size 1.27 1.27)
				)
				(justify left bottom)
				(hide yes)
			)
		)
		(property "Dielectric" "X5R"
			(at 217.17 93.98 0)
			(effects
				(font
					(size 1.27 1.27)
				)
				(justify left bottom)
				(hide yes)
			)
		)
		(pin "2"
		)
		(pin "1"
		)
		(instances
			(project "thunderbolt-to-10gbe-adapter"
				(path ""
					(reference "C121")
					(unit 1)
				)
			)
		)
	)
	(symbol
		(lib_id "antmicroResistors0402:R_30k_0402")
		(at 332.74 80.01 90)
		(unit 1)
		(exclude_from_sim no)
		(in_bom yes)
		(on_board yes)
		(dnp no)
		(property "Reference" "R101"
			(at 334.01 76.2 90)
			(effects
				(font
					(size 1.27 1.27)
					(thickness 0.15)
				)
				(justify right)
			)
		)
		(property "Value" "R_30k_0402"
			(at 345.44 59.69 0)
			(effects
				(font
					(size 1.27 1.27)
					(thickness 0.15)
				)
				(justify left bottom)
				(hide yes)
			)
		)
		(property "Footprint" "antmicro-footprints:R_0402_1005Metric"
			(at 347.98 59.69 0)
			(effects
				(font
					(size 1.27 1.27)
					(thickness 0.15)
				)
				(justify left bottom)
				(hide yes)
			)
		)
		(property "Datasheet" "https://www.bourns.com/docs/product-datasheets/cr.pdf"
			(at 350.52 59.69 0)
			(effects
				(font
					(size 1.27 1.27)
					(thickness 0.15)
				)
				(justify left bottom)
				(hide yes)
			)
		)
		(property "Description" "SMD Chip Resistor, 30 kohm, ± 1%, 63 mW, 0402 [1005 Metric], Thick Film, General Purpose"
			(at 363.22 59.69 0)
			(effects
				(font
					(size 1.27 1.27)
				)
				(justify left bottom)
				(hide yes)
			)
		)
		(property "MPN" "CR0402-FX-3002GLF"
			(at 353.06 59.69 0)
			(effects
				(font
					(size 1.27 1.27)
					(thickness 0.15)
				)
				(justify left bottom)
				(hide yes)
			)
		)
		(property "Manufacturer" "Bourns"
			(at 355.6 59.69 0)
			(effects
				(font
					(size 1.27 1.27)
					(thickness 0.15)
				)
				(justify left bottom)
				(hide yes)
			)
		)
		(property "License" "Apache-2.0"
			(at 358.14 59.69 0)
			(effects
				(font
					(size 1.27 1.27)
					(thickness 0.15)
				)
				(justify left bottom)
				(hide yes)
			)
		)
		(property "Author" "Antmicro"
			(at 360.68 59.69 0)
			(effects
				(font
					(size 1.27 1.27)
					(thickness 0.15)
				)
				(justify left bottom)
				(hide yes)
			)
		)
		(property "Val" "30k"
			(at 334.01 78.74 90)
			(effects
				(font
					(size 1.27 1.27)
					(thickness 0.15)
				)
				(justify right)
			)
		)
		(property "Tolerance" "1%"
			(at 342.9 59.69 0)
			(effects
				(font
					(size 1.27 1.27)
				)
				(justify left bottom)
				(hide yes)
			)
		)
		(pin "2"
		)
		(pin "1"
		)
		(instances
			(project "thunderbolt-to-10gbe-adapter"
				(path ""
					(reference "R101")
					(unit 1)
				)
			)
		)
	)
	(symbol
		(lib_id "antmicroCapacitors0402:C_33p_0402")
		(at 327.66 109.22 270)
		(mirror x)
		(unit 1)
		(exclude_from_sim no)
		(in_bom yes)
		(on_board yes)
		(dnp yes)
		(property "Reference" "C131"
			(at 325.882 105.41 90)
			(effects
				(font
					(size 1.27 1.27)
					(thickness 0.15)
				)
				(justify right)
			)
		)
		(property "Value" "C_33p_0402"
			(at 317.5 88.9 0)
			(effects
				(font
					(size 1.27 1.27)
					(thickness 0.15)
				)
				(justify left bottom)
				(hide yes)
			)
		)
		(property "Footprint" "antmicro-footprints:C_0402_1005Metric"
			(at 314.96 88.9 0)
			(effects
				(font
					(size 1.27 1.27)
					(thickness 0.15)
				)
				(justify left bottom)
				(hide yes)
			)
		)
		(property "Datasheet" "https://spicat.kyocera-avx.com/product/mlcc/chartview/04025A330FAT2A/"
			(at 312.42 88.9 0)
			(effects
				(font
					(size 1.27 1.27)
					(thickness 0.15)
				)
				(justify left bottom)
				(hide yes)
			)
		)
		(property "Description" "SMD Multilayer Ceramic Capacitor, 33 pF, 50 V, 0402 [1005 Metric], ± 5%, C0G / NP0, MC"
			(at 294.64 88.9 0)
			(effects
				(font
					(size 1.27 1.27)
				)
				(justify left bottom)
				(hide yes)
			)
		)
		(property "MPN" "04025A330FAT2A"
			(at 309.88 88.9 0)
			(effects
				(font
					(size 1.27 1.27)
					(thickness 0.15)
				)
				(justify left bottom)
				(hide yes)
			)
		)
		(property "Manufacturer" "KYOCERA AVX"
			(at 307.34 88.9 0)
			(effects
				(font
					(size 1.27 1.27)
					(thickness 0.15)
				)
				(justify left bottom)
				(hide yes)
			)
		)
		(property "License" "Apache-2.0"
			(at 304.8 88.9 0)
			(effects
				(font
					(size 1.27 1.27)
					(thickness 0.15)
				)
				(justify left bottom)
				(hide yes)
			)
		)
		(property "Author" "Antmicro"
			(at 302.26 88.9 0)
			(effects
				(font
					(size 1.27 1.27)
					(thickness 0.15)
				)
				(justify left bottom)
				(hide yes)
			)
		)
		(property "Val" "33p"
			(at 325.882 107.95 90)
			(effects
				(font
					(size 1.27 1.27)
					(thickness 0.15)
				)
				(justify right)
			)
		)
		(property "Voltage" ""
			(at 299.72 88.9 0)
			(effects
				(font
					(size 1.27 1.27)
				)
				(justify left bottom)
				(hide yes)
			)
		)
		(property "Dielectric" ""
			(at 297.18 88.9 0)
			(effects
				(font
					(size 1.27 1.27)
				)
				(justify left bottom)
				(hide yes)
			)
		)
		(pin "2"
		)
		(pin "1"
		)
		(instances
			(project "thunderbolt-to-10gbe-adapter"
				(path ""
					(reference "C131")
					(unit 1)
				)
			)
		)
	)
	(symbol
		(lib_id "antmicropower:GND")
		(at 332.74 43.18 0)
		(unit 1)
		(exclude_from_sim no)
		(in_bom yes)
		(on_board yes)
		(dnp no)
		(property "Reference" "#PWR0183"
			(at 341.63 45.72 0)
			(effects
				(font
					(size 1.27 1.27)
					(thickness 0.15)
				)
				(justify left bottom)
				(hide yes)
			)
		)
		(property "Value" "GND"
			(at 332.74 46.99 0)
			(effects
				(font
					(size 1.27 1.27)
					(thickness 0.15)
				)
			)
		)
		(property "Footprint" ""
			(at 341.63 50.8 0)
			(effects
				(font
					(size 1.27 1.27)
					(thickness 0.15)
				)
				(justify left bottom)
				(hide yes)
			)
		)
		(property "Datasheet" ""
			(at 341.63 55.88 0)
			(effects
				(font
					(size 1.27 1.27)
					(thickness 0.15)
				)
				(justify left bottom)
				(hide yes)
			)
		)
		(property "Description" ""
			(at 332.74 43.18 0)
			(effects
				(font
					(size 1.27 1.27)
				)
				(hide yes)
			)
		)
		(property "Author" "Antmicro"
			(at 341.63 50.8 0)
			(effects
				(font
					(size 1.27 1.27)
					(thickness 0.15)
				)
				(justify left bottom)
				(hide yes)
			)
		)
		(property "License" "Apache-2.0"
			(at 341.63 53.34 0)
			(effects
				(font
					(size 1.27 1.27)
					(thickness 0.15)
				)
				(justify left bottom)
				(hide yes)
			)
		)
		(pin "1"
		)
		(instances
			(project "thunderbolt-to-10gbe-adapter"
				(path ""
					(reference "#PWR0183")
					(unit 1)
				)
			)
		)
	)
	(symbol
		(lib_id "antmicroCapacitors0402:C_100n_0402")
		(at 237.49 190.5 270)
		(mirror x)
		(unit 1)
		(exclude_from_sim no)
		(in_bom yes)
		(on_board yes)
		(dnp no)
		(property "Reference" "C118"
			(at 235.712 186.69 90)
			(effects
				(font
					(size 1.27 1.27)
					(thickness 0.15)
				)
				(justify right)
			)
		)
		(property "Value" "C_100n_0402"
			(at 227.33 170.18 0)
			(effects
				(font
					(size 1.27 1.27)
					(thickness 0.15)
				)
				(justify left bottom)
				(hide yes)
			)
		)
		(property "Footprint" "antmicro-footprints:C_0402_1005Metric"
			(at 224.79 170.18 0)
			(effects
				(font
					(size 1.27 1.27)
					(thickness 0.15)
				)
				(justify left bottom)
				(hide yes)
			)
		)
		(property "Datasheet" "https://www.murata.com/products/productdetail?partno=GRM155R61H104KE14%23"
			(at 222.25 170.18 0)
			(effects
				(font
					(size 1.27 1.27)
					(thickness 0.15)
				)
				(justify left bottom)
				(hide yes)
			)
		)
		(property "Description" "SMD Multilayer Ceramic Capacitor, 0.1 µF, 50 V, 0402 [1005 Metric], ± 10%, X5R, GRM Series"
			(at 204.47 170.18 0)
			(effects
				(font
					(size 1.27 1.27)
				)
				(justify left bottom)
				(hide yes)
			)
		)
		(property "MPN" "GRM155R61H104KE14D"
			(at 219.71 170.18 0)
			(effects
				(font
					(size 1.27 1.27)
					(thickness 0.15)
				)
				(justify left bottom)
				(hide yes)
			)
		)
		(property "Manufacturer" "Murata"
			(at 217.17 170.18 0)
			(effects
				(font
					(size 1.27 1.27)
					(thickness 0.15)
				)
				(justify left bottom)
				(hide yes)
			)
		)
		(property "License" "Apache-2.0"
			(at 214.63 170.18 0)
			(effects
				(font
					(size 1.27 1.27)
					(thickness 0.15)
				)
				(justify left bottom)
				(hide yes)
			)
		)
		(property "Author" "Antmicro"
			(at 212.09 170.18 0)
			(effects
				(font
					(size 1.27 1.27)
					(thickness 0.15)
				)
				(justify left bottom)
				(hide yes)
			)
		)
		(property "Val" "100n"
			(at 235.712 189.23 90)
			(effects
				(font
					(size 1.27 1.27)
					(thickness 0.15)
				)
				(justify right)
			)
		)
		(property "Voltage" "50V"
			(at 209.55 170.18 0)
			(effects
				(font
					(size 1.27 1.27)
				)
				(justify left bottom)
				(hide yes)
			)
		)
		(property "Dielectric" "X5R"
			(at 207.01 170.18 0)
			(effects
				(font
					(size 1.27 1.27)
				)
				(justify left bottom)
				(hide yes)
			)
		)
		(pin "1"
		)
		(pin "2"
		)
		(instances
			(project "thunderbolt-to-10gbe-adapter"
				(path ""
					(reference "C118")
					(unit 1)
				)
			)
		)
	)
	(symbol
		(lib_id "antmicropower:GND")
		(at 364.49 195.58 0)
		(unit 1)
		(exclude_from_sim no)
		(in_bom yes)
		(on_board yes)
		(dnp no)
		(property "Reference" "#PWR0202"
			(at 373.38 198.12 0)
			(effects
				(font
					(size 1.27 1.27)
					(thickness 0.15)
				)
				(justify left bottom)
				(hide yes)
			)
		)
		(property "Value" "GND"
			(at 364.49 199.39 0)
			(effects
				(font
					(size 1.27 1.27)
					(thickness 0.15)
				)
			)
		)
		(property "Footprint" ""
			(at 373.38 203.2 0)
			(effects
				(font
					(size 1.27 1.27)
					(thickness 0.15)
				)
				(justify left bottom)
				(hide yes)
			)
		)
		(property "Datasheet" ""
			(at 373.38 208.28 0)
			(effects
				(font
					(size 1.27 1.27)
					(thickness 0.15)
				)
				(justify left bottom)
				(hide yes)
			)
		)
		(property "Description" ""
			(at 364.49 195.58 0)
			(effects
				(font
					(size 1.27 1.27)
				)
				(hide yes)
			)
		)
		(property "Author" "Antmicro"
			(at 373.38 203.2 0)
			(effects
				(font
					(size 1.27 1.27)
					(thickness 0.15)
				)
				(justify left bottom)
				(hide yes)
			)
		)
		(property "License" "Apache-2.0"
			(at 373.38 205.74 0)
			(effects
				(font
					(size 1.27 1.27)
					(thickness 0.15)
				)
				(justify left bottom)
				(hide yes)
			)
		)
		(pin "1"
		)
		(instances
			(project "thunderbolt-to-10gbe-adapter"
				(path ""
					(reference "#PWR0202")
					(unit 1)
				)
			)
		)
	)
	(symbol
		(lib_id "antmicroLEDIndicationDiscrete:LED_G_0603_LG_L29K-G2J1-24-Z")
		(at 203.2 223.52 90)
		(unit 1)
		(exclude_from_sim no)
		(in_bom yes)
		(on_board yes)
		(dnp no)
		(property "Reference" "D7"
			(at 204.47 219.71 90)
			(effects
				(font
					(size 1.27 1.27)
					(thickness 0.15)
				)
				(justify right)
			)
		)
		(property "Value" "LED_G_0603_LG_L29K-G2J1-24-Z"
			(at 210.82 203.2 0)
			(effects
				(font
					(size 1.27 1.27)
					(thickness 0.15)
				)
				(justify left bottom)
				(hide yes)
			)
		)
		(property "Footprint" "antmicro-footprints:LED_0603_1608Metric_G"
			(at 213.36 203.2 0)
			(effects
				(font
					(size 1.27 1.27)
					(thickness 0.15)
				)
				(justify left bottom)
				(hide yes)
			)
		)
		(property "Datasheet" "https://look.ams-osram.com/m/19ee86b3ae0ee95b/original/LG-L29K.pdf"
			(at 215.9 203.2 0)
			(effects
				(font
					(size 1.27 1.27)
					(thickness 0.15)
				)
				(justify left bottom)
				(hide yes)
			)
		)
		(property "Description" "LED, Green, SMD, 0603, 20 mA, 1.7 V, 570 nm"
			(at 203.2 223.52 0)
			(effects
				(font
					(size 1.27 1.27)
				)
				(hide yes)
			)
		)
		(property "MPN" "LG L29K-G2J1-24-Z"
			(at 218.44 203.2 0)
			(effects
				(font
					(size 1.27 1.27)
					(thickness 0.15)
				)
				(justify left bottom)
				(hide yes)
			)
		)
		(property "Manufacturer" "OSRAM"
			(at 220.98 203.2 0)
			(effects
				(font
					(size 1.27 1.27)
					(thickness 0.15)
				)
				(justify left bottom)
				(hide yes)
			)
		)
		(property "Color" "Green"
			(at 204.47 222.2499 90)
			(effects
				(font
					(size 1.27 1.27)
				)
				(justify right)
			)
		)
		(property "Author" "Antmicro"
			(at 223.52 203.2 0)
			(effects
				(font
					(size 1.27 1.27)
					(thickness 0.15)
				)
				(justify left bottom)
				(hide yes)
			)
		)
		(property "License" "Apache-2.0"
			(at 226.06 203.2 0)
			(effects
				(font
					(size 1.27 1.27)
					(thickness 0.15)
				)
				(justify left bottom)
				(hide yes)
			)
		)
		(pin "2"
		)
		(pin "1"
		)
		(instances
			(project "thunderbolt-to-10gbe-adapter"
				(path ""
					(reference "D7")
					(unit 1)
				)
			)
		)
	)
	(symbol
		(lib_id "antmicropower:GND")
		(at 254 246.38 0)
		(mirror y)
		(unit 1)
		(exclude_from_sim no)
		(in_bom yes)
		(on_board yes)
		(dnp no)
		(property "Reference" "#PWR0175"
			(at 245.11 248.92 0)
			(effects
				(font
					(size 1.27 1.27)
					(thickness 0.15)
				)
				(justify left bottom)
				(hide yes)
			)
		)
		(property "Value" "GND"
			(at 254 250.19 0)
			(effects
				(font
					(size 1.27 1.27)
					(thickness 0.15)
				)
			)
		)
		(property "Footprint" ""
			(at 245.11 254 0)
			(effects
				(font
					(size 1.27 1.27)
					(thickness 0.15)
				)
				(justify left bottom)
				(hide yes)
			)
		)
		(property "Datasheet" ""
			(at 245.11 259.08 0)
			(effects
				(font
					(size 1.27 1.27)
					(thickness 0.15)
				)
				(justify left bottom)
				(hide yes)
			)
		)
		(property "Description" ""
			(at 254 246.38 0)
			(effects
				(font
					(size 1.27 1.27)
				)
				(hide yes)
			)
		)
		(property "Author" "Antmicro"
			(at 245.11 254 0)
			(effects
				(font
					(size 1.27 1.27)
					(thickness 0.15)
				)
				(justify left bottom)
				(hide yes)
			)
		)
		(property "License" "Apache-2.0"
			(at 245.11 256.54 0)
			(effects
				(font
					(size 1.27 1.27)
					(thickness 0.15)
				)
				(justify left bottom)
				(hide yes)
			)
		)
		(pin "1"
		)
		(instances
			(project "thunderbolt-to-10gbe-adapter"
				(path ""
					(reference "#PWR0175")
					(unit 1)
				)
			)
		)
	)
	(symbol
		(lib_id "antmicropower:+1V0")
		(at 400.05 137.16 0)
		(unit 1)
		(exclude_from_sim no)
		(in_bom yes)
		(on_board yes)
		(dnp no)
		(property "Reference" "#PWR0216"
			(at 400.05 140.97 0)
			(effects
				(font
					(size 1.27 1.27)
				)
				(hide yes)
			)
		)
		(property "Value" "+1V0"
			(at 400.05 133.35 0)
			(effects
				(font
					(size 1.27 1.27)
				)
			)
		)
		(property "Footprint" ""
			(at 400.05 137.16 0)
			(effects
				(font
					(size 1.27 1.27)
				)
				(hide yes)
			)
		)
		(property "Datasheet" ""
			(at 400.05 137.16 0)
			(effects
				(font
					(size 1.27 1.27)
				)
				(hide yes)
			)
		)
		(property "Description" ""
			(at 400.05 137.16 0)
			(effects
				(font
					(size 1.27 1.27)
				)
				(hide yes)
			)
		)
		(pin "1"
		)
		(instances
			(project "thunderbolt-to-10gbe-adapter"
				(path ""
					(reference "#PWR0216")
					(unit 1)
				)
			)
		)
	)
	(symbol
		(lib_id "antmicroResistors0402:R_30k_0402")
		(at 332.74 156.21 90)
		(unit 1)
		(exclude_from_sim no)
		(in_bom yes)
		(on_board yes)
		(dnp no)
		(property "Reference" "R105"
			(at 334.01 152.4 90)
			(effects
				(font
					(size 1.27 1.27)
					(thickness 0.15)
				)
				(justify right)
			)
		)
		(property "Value" "R_30k_0402"
			(at 345.44 135.89 0)
			(effects
				(font
					(size 1.27 1.27)
					(thickness 0.15)
				)
				(justify left bottom)
				(hide yes)
			)
		)
		(property "Footprint" "antmicro-footprints:R_0402_1005Metric"
			(at 347.98 135.89 0)
			(effects
				(font
					(size 1.27 1.27)
					(thickness 0.15)
				)
				(justify left bottom)
				(hide yes)
			)
		)
		(property "Datasheet" "https://www.bourns.com/docs/product-datasheets/cr.pdf"
			(at 350.52 135.89 0)
			(effects
				(font
					(size 1.27 1.27)
					(thickness 0.15)
				)
				(justify left bottom)
				(hide yes)
			)
		)
		(property "Description" "SMD Chip Resistor, 30 kohm, ± 1%, 63 mW, 0402 [1005 Metric], Thick Film, General Purpose"
			(at 363.22 135.89 0)
			(effects
				(font
					(size 1.27 1.27)
				)
				(justify left bottom)
				(hide yes)
			)
		)
		(property "MPN" "CR0402-FX-3002GLF"
			(at 353.06 135.89 0)
			(effects
				(font
					(size 1.27 1.27)
					(thickness 0.15)
				)
				(justify left bottom)
				(hide yes)
			)
		)
		(property "Manufacturer" "Bourns"
			(at 355.6 135.89 0)
			(effects
				(font
					(size 1.27 1.27)
					(thickness 0.15)
				)
				(justify left bottom)
				(hide yes)
			)
		)
		(property "License" "Apache-2.0"
			(at 358.14 135.89 0)
			(effects
				(font
					(size 1.27 1.27)
					(thickness 0.15)
				)
				(justify left bottom)
				(hide yes)
			)
		)
		(property "Author" "Antmicro"
			(at 360.68 135.89 0)
			(effects
				(font
					(size 1.27 1.27)
					(thickness 0.15)
				)
				(justify left bottom)
				(hide yes)
			)
		)
		(property "Val" "30k"
			(at 334.01 154.94 90)
			(effects
				(font
					(size 1.27 1.27)
					(thickness 0.15)
				)
				(justify right)
			)
		)
		(property "Tolerance" "1%"
			(at 342.9 135.89 0)
			(effects
				(font
					(size 1.27 1.27)
				)
				(justify left bottom)
				(hide yes)
			)
		)
		(pin "2"
		)
		(pin "1"
		)
		(instances
			(project "thunderbolt-to-10gbe-adapter"
				(path ""
					(reference "R105")
					(unit 1)
				)
			)
		)
	)
	(symbol
		(lib_id "antmicroDCDCConverters:TPS566231P")
		(at 276.86 101.6 0)
		(unit 1)
		(exclude_from_sim no)
		(in_bom yes)
		(on_board yes)
		(dnp no)
		(fields_autoplaced yes)
		(property "Reference" "U11"
			(at 285.75 95.25 0)
			(effects
				(font
					(size 1.27 1.27)
					(thickness 0.15)
				)
			)
		)
		(property "Value" "TPS566231P"
			(at 309.88 106.68 0)
			(effects
				(font
					(size 1.27 1.27)
					(thickness 0.15)
				)
				(justify left bottom)
				(hide yes)
			)
		)
		(property "Footprint" "antmicro-footprints:VQFN-HR-9_2x1.5mm"
			(at 309.88 109.22 0)
			(effects
				(font
					(size 1.27 1.27)
					(thickness 0.15)
				)
				(justify left bottom)
				(hide yes)
			)
		)
		(property "Datasheet" "https://www.ti.com/lit/ds/symlink/tps566231.pdf"
			(at 309.88 111.76 0)
			(effects
				(font
					(size 1.27 1.27)
					(thickness 0.15)
				)
				(justify left bottom)
				(hide yes)
			)
		)
		(property "Description" "Switching Voltage Regulators 3-V to 18-V, 6-A synchronous buck converter"
			(at 309.88 124.46 0)
			(effects
				(font
					(size 1.27 1.27)
				)
				(justify left bottom)
				(hide yes)
			)
		)
		(property "Manufacturer" "Texas Instruments"
			(at 309.88 114.3 0)
			(effects
				(font
					(size 1.27 1.27)
					(thickness 0.15)
				)
				(justify left bottom)
				(hide yes)
			)
		)
		(property "MPN" "TPS566231PRQFR"
			(at 285.75 97.79 0)
			(effects
				(font
					(size 1.27 1.27)
					(thickness 0.15)
				)
			)
		)
		(property "Author" "Antmicro"
			(at 309.88 119.38 0)
			(effects
				(font
					(size 1.27 1.27)
					(thickness 0.15)
				)
				(justify left bottom)
				(hide yes)
			)
		)
		(property "License" "Apache-2.0"
			(at 309.88 121.92 0)
			(effects
				(font
					(size 1.27 1.27)
					(thickness 0.15)
				)
				(justify left bottom)
				(hide yes)
			)
		)
		(pin "1"
		)
		(pin "2"
		)
		(pin "3"
		)
		(pin "9"
		)
		(pin "5"
		)
		(pin "6"
		)
		(pin "8"
		)
		(pin "4"
		)
		(pin "7"
		)
		(instances
			(project "thunderbolt-to-10gbe-adapter"
				(path ""
					(reference "U11")
					(unit 1)
				)
			)
		)
	)
	(symbol
		(lib_id "antmicroCapacitors0603:C_22u_16V_0603")
		(at 364.49 76.2 90)
		(unit 1)
		(exclude_from_sim no)
		(in_bom yes)
		(on_board yes)
		(dnp no)
		(property "Reference" "C145"
			(at 366.268 72.39 90)
			(effects
				(font
					(size 1.27 1.27)
					(thickness 0.15)
				)
				(justify right)
			)
		)
		(property "Value" "C_22u_16V_0603"
			(at 374.65 55.88 0)
			(effects
				(font
					(size 1.27 1.27)
					(thickness 0.15)
				)
				(justify left bottom)
				(hide yes)
			)
		)
		(property "Footprint" "antmicro-footprints:C_0603_1608Metric_EIA"
			(at 377.19 55.88 0)
			(effects
				(font
					(size 1.27 1.27)
					(thickness 0.15)
				)
				(justify left bottom)
				(hide yes)
			)
		)
		(property "Datasheet" "https://product.samsungsem.com/mlcc/CL10A226MO7JZN.do"
			(at 379.73 55.88 0)
			(effects
				(font
					(size 1.27 1.27)
					(thickness 0.15)
				)
				(justify left bottom)
				(hide yes)
			)
		)
		(property "Description" "SMD Multilayer Ceramic Capacitor"
			(at 364.49 76.2 0)
			(effects
				(font
					(size 1.27 1.27)
				)
				(hide yes)
			)
		)
		(property "MPN" "CL10A226MO7JZNC"
			(at 382.27 55.88 0)
			(effects
				(font
					(size 1.27 1.27)
					(thickness 0.15)
				)
				(justify left bottom)
				(hide yes)
			)
		)
		(property "Manufacturer" "Samsung Electro-Mechanics"
			(at 384.81 55.88 0)
			(effects
				(font
					(size 1.27 1.27)
					(thickness 0.15)
				)
				(justify left bottom)
				(hide yes)
			)
		)
		(property "License" "Apache-2.0"
			(at 387.35 55.88 0)
			(effects
				(font
					(size 1.27 1.27)
					(thickness 0.15)
				)
				(justify left bottom)
				(hide yes)
			)
		)
		(property "Author" "Antmicro"
			(at 389.89 55.88 0)
			(effects
				(font
					(size 1.27 1.27)
					(thickness 0.15)
				)
				(justify left bottom)
				(hide yes)
			)
		)
		(property "Val" "22u"
			(at 366.268 74.93 90)
			(effects
				(font
					(size 1.27 1.27)
					(thickness 0.15)
				)
				(justify right)
			)
		)
		(property "Voltage" "16V"
			(at 367.03 76.1935 90)
			(effects
				(font
					(size 1.27 1.27)
				)
				(justify right)
				(hide yes)
			)
		)
		(property "Dielectric" ""
			(at 394.97 55.88 0)
			(effects
				(font
					(size 1.27 1.27)
				)
				(justify left bottom)
				(hide yes)
			)
		)
		(pin "2"
		)
		(pin "1"
		)
		(instances
			(project "thunderbolt-to-10gbe-adapter"
				(path ""
					(reference "C145")
					(unit 1)
				)
			)
		)
	)
	(symbol
		(lib_id "antmicroCapacitors0402:C_100n_0402")
		(at 237.49 76.2 270)
		(mirror x)
		(unit 1)
		(exclude_from_sim no)
		(in_bom yes)
		(on_board yes)
		(dnp no)
		(property "Reference" "C115"
			(at 235.712 72.39 90)
			(effects
				(font
					(size 1.27 1.27)
					(thickness 0.15)
				)
				(justify right)
			)
		)
		(property "Value" "C_100n_0402"
			(at 227.33 55.88 0)
			(effects
				(font
					(size 1.27 1.27)
					(thickness 0.15)
				)
				(justify left bottom)
				(hide yes)
			)
		)
		(property "Footprint" "antmicro-footprints:C_0402_1005Metric"
			(at 224.79 55.88 0)
			(effects
				(font
					(size 1.27 1.27)
					(thickness 0.15)
				)
				(justify left bottom)
				(hide yes)
			)
		)
		(property "Datasheet" "https://www.murata.com/products/productdetail?partno=GRM155R61H104KE14%23"
			(at 222.25 55.88 0)
			(effects
				(font
					(size 1.27 1.27)
					(thickness 0.15)
				)
				(justify left bottom)
				(hide yes)
			)
		)
		(property "Description" "SMD Multilayer Ceramic Capacitor, 0.1 µF, 50 V, 0402 [1005 Metric], ± 10%, X5R, GRM Series"
			(at 204.47 55.88 0)
			(effects
				(font
					(size 1.27 1.27)
				)
				(justify left bottom)
				(hide yes)
			)
		)
		(property "MPN" "GRM155R61H104KE14D"
			(at 219.71 55.88 0)
			(effects
				(font
					(size 1.27 1.27)
					(thickness 0.15)
				)
				(justify left bottom)
				(hide yes)
			)
		)
		(property "Manufacturer" "Murata"
			(at 217.17 55.88 0)
			(effects
				(font
					(size 1.27 1.27)
					(thickness 0.15)
				)
				(justify left bottom)
				(hide yes)
			)
		)
		(property "License" "Apache-2.0"
			(at 214.63 55.88 0)
			(effects
				(font
					(size 1.27 1.27)
					(thickness 0.15)
				)
				(justify left bottom)
				(hide yes)
			)
		)
		(property "Author" "Antmicro"
			(at 212.09 55.88 0)
			(effects
				(font
					(size 1.27 1.27)
					(thickness 0.15)
				)
				(justify left bottom)
				(hide yes)
			)
		)
		(property "Val" "100n"
			(at 235.712 74.93 90)
			(effects
				(font
					(size 1.27 1.27)
					(thickness 0.15)
				)
				(justify right)
			)
		)
		(property "Voltage" "50V"
			(at 209.55 55.88 0)
			(effects
				(font
					(size 1.27 1.27)
				)
				(justify left bottom)
				(hide yes)
			)
		)
		(property "Dielectric" "X5R"
			(at 207.01 55.88 0)
			(effects
				(font
					(size 1.27 1.27)
				)
				(justify left bottom)
				(hide yes)
			)
		)
		(pin "1"
		)
		(pin "2"
		)
		(instances
			(project "thunderbolt-to-10gbe-adapter"
				(path ""
					(reference "C115")
					(unit 1)
				)
			)
		)
	)
	(symbol
		(lib_id "antmicropower:GND")
		(at 237.49 43.18 0)
		(unit 1)
		(exclude_from_sim no)
		(in_bom yes)
		(on_board yes)
		(dnp no)
		(property "Reference" "#PWR0165"
			(at 246.38 45.72 0)
			(effects
				(font
					(size 1.27 1.27)
					(thickness 0.15)
				)
				(justify left bottom)
				(hide yes)
			)
		)
		(property "Value" "GND"
			(at 237.49 46.99 0)
			(effects
				(font
					(size 1.27 1.27)
					(thickness 0.15)
				)
			)
		)
		(property "Footprint" ""
			(at 246.38 50.8 0)
			(effects
				(font
					(size 1.27 1.27)
					(thickness 0.15)
				)
				(justify left bottom)
				(hide yes)
			)
		)
		(property "Datasheet" ""
			(at 246.38 55.88 0)
			(effects
				(font
					(size 1.27 1.27)
					(thickness 0.15)
				)
				(justify left bottom)
				(hide yes)
			)
		)
		(property "Description" ""
			(at 237.49 43.18 0)
			(effects
				(font
					(size 1.27 1.27)
				)
				(hide yes)
			)
		)
		(property "Author" "Antmicro"
			(at 246.38 50.8 0)
			(effects
				(font
					(size 1.27 1.27)
					(thickness 0.15)
				)
				(justify left bottom)
				(hide yes)
			)
		)
		(property "License" "Apache-2.0"
			(at 246.38 53.34 0)
			(effects
				(font
					(size 1.27 1.27)
					(thickness 0.15)
				)
				(justify left bottom)
				(hide yes)
			)
		)
		(pin "1"
		)
		(instances
			(project "thunderbolt-to-10gbe-adapter"
				(path ""
					(reference "#PWR0165")
					(unit 1)
				)
			)
		)
	)
	(symbol
		(lib_id "antmicroTestPoints:TP_0.75mm_SMD")
		(at 391.16 241.3 0)
		(unit 1)
		(exclude_from_sim no)
		(in_bom no)
		(on_board yes)
		(dnp no)
		(fields_autoplaced yes)
		(property "Reference" "TP5"
			(at 396.24 241.3 0)
			(effects
				(font
					(size 1.27 1.27)
					(thickness 0.15)
				)
				(justify left)
			)
		)
		(property "Value" "TP_0.75mm_SMD"
			(at 401.32 245.11 0)
			(effects
				(font
					(size 1.27 1.27)
					(thickness 0.15)
				)
				(justify left bottom)
				(hide yes)
			)
		)
		(property "Footprint" "antmicro-footprints:TP_SMD_0.75mm"
			(at 401.32 247.65 0)
			(effects
				(font
					(size 1.27 1.27)
					(thickness 0.15)
				)
				(justify left bottom)
				(hide yes)
			)
		)
		(property "Datasheet" ""
			(at 408.94 254 0)
			(effects
				(font
					(size 1.27 1.27)
					(thickness 0.15)
				)
				(justify left bottom)
				(hide yes)
			)
		)
		(property "Description" "SMT test point"
			(at 401.955 255.27 0)
			(effects
				(font
					(size 1.27 1.27)
				)
				(justify left bottom)
				(hide yes)
			)
		)
		(property "MPN" ""
			(at 401.955 252.73 0)
			(effects
				(font
					(size 1.27 1.27)
					(thickness 0.15)
				)
				(justify left bottom)
				(hide yes)
			)
		)
		(property "Manufacturer" ""
			(at 401.955 247.65 0)
			(effects
				(font
					(size 1.27 1.27)
					(thickness 0.15)
				)
				(justify left bottom)
				(hide yes)
			)
		)
		(property "Author" "Antmicro"
			(at 401.32 250.19 0)
			(effects
				(font
					(size 1.27 1.27)
					(thickness 0.15)
				)
				(justify left bottom)
				(hide yes)
			)
		)
		(property "License" "Apache-2.0"
			(at 401.32 252.73 0)
			(effects
				(font
					(size 1.27 1.27)
					(thickness 0.15)
				)
				(justify left bottom)
				(hide yes)
			)
		)
		(pin "1"
		)
		(instances
			(project "thunderbolt-to-10gbe-adapter"
				(path ""
					(reference "TP5")
					(unit 1)
				)
			)
		)
	)
	(symbol
		(lib_id "antmicroCapacitors0402:C_1u_25V_0402")
		(at 247.65 38.1 270)
		(mirror x)
		(unit 1)
		(exclude_from_sim no)
		(in_bom yes)
		(on_board yes)
		(dnp no)
		(property "Reference" "C119"
			(at 245.872 34.29 90)
			(effects
				(font
					(size 1.27 1.27)
					(thickness 0.15)
				)
				(justify right)
			)
		)
		(property "Value" "C_1u_25V_0402"
			(at 237.49 17.78 0)
			(effects
				(font
					(size 1.27 1.27)
					(thickness 0.15)
				)
				(justify left bottom)
				(hide yes)
			)
		)
		(property "Footprint" "antmicro-footprints:C_0402_1005Metric"
			(at 234.95 17.78 0)
			(effects
				(font
					(size 1.27 1.27)
					(thickness 0.15)
				)
				(justify left bottom)
				(hide yes)
			)
		)
		(property "Datasheet" "https://www.murata.com/products/productdetail?partno=GRM155R61E105KE11%23"
			(at 232.41 17.78 0)
			(effects
				(font
					(size 1.27 1.27)
					(thickness 0.15)
				)
				(justify left bottom)
				(hide yes)
			)
		)
		(property "Description" "SMD Multilayer Ceramic Capacitor, 1 µF, 25 V, 0402 [1005 Metric], ± 10%, X5R, GRM Series"
			(at 214.63 17.78 0)
			(effects
				(font
					(size 1.27 1.27)
				)
				(justify left bottom)
				(hide yes)
			)
		)
		(property "MPN" "GRM155R61E105KE11J"
			(at 229.87 17.78 0)
			(effects
				(font
					(size 1.27 1.27)
					(thickness 0.15)
				)
				(justify left bottom)
				(hide yes)
			)
		)
		(property "Manufacturer" "Murata"
			(at 227.33 17.78 0)
			(effects
				(font
					(size 1.27 1.27)
					(thickness 0.15)
				)
				(justify left bottom)
				(hide yes)
			)
		)
		(property "License" "Apache-2.0"
			(at 224.79 17.78 0)
			(effects
				(font
					(size 1.27 1.27)
					(thickness 0.15)
				)
				(justify left bottom)
				(hide yes)
			)
		)
		(property "Author" "Antmicro"
			(at 222.25 17.78 0)
			(effects
				(font
					(size 1.27 1.27)
					(thickness 0.15)
				)
				(justify left bottom)
				(hide yes)
			)
		)
		(property "Val" "1u"
			(at 245.872 36.83 90)
			(effects
				(font
					(size 1.27 1.27)
					(thickness 0.15)
				)
				(justify right)
			)
		)
		(property "Voltage" "25V"
			(at 219.71 17.78 0)
			(effects
				(font
					(size 1.27 1.27)
				)
				(justify left bottom)
				(hide yes)
			)
		)
		(property "Dielectric" "X5R"
			(at 217.17 17.78 0)
			(effects
				(font
					(size 1.27 1.27)
				)
				(justify left bottom)
				(hide yes)
			)
		)
		(pin "2"
		)
		(pin "1"
		)
		(instances
			(project "thunderbolt-to-10gbe-adapter"
				(path ""
					(reference "C119")
					(unit 1)
				)
			)
		)
	)
	(symbol
		(lib_id "antmicroCapacitors0603:C_22u_16V_0603")
		(at 364.49 38.1 90)
		(unit 1)
		(exclude_from_sim no)
		(in_bom yes)
		(on_board yes)
		(dnp no)
		(property "Reference" "C144"
			(at 366.268 34.29 90)
			(effects
				(font
					(size 1.27 1.27)
					(thickness 0.15)
				)
				(justify right)
			)
		)
		(property "Value" "C_22u_16V_0603"
			(at 374.65 17.78 0)
			(effects
				(font
					(size 1.27 1.27)
					(thickness 0.15)
				)
				(justify left bottom)
				(hide yes)
			)
		)
		(property "Footprint" "antmicro-footprints:C_0603_1608Metric_EIA"
			(at 377.19 17.78 0)
			(effects
				(font
					(size 1.27 1.27)
					(thickness 0.15)
				)
				(justify left bottom)
				(hide yes)
			)
		)
		(property "Datasheet" "https://product.samsungsem.com/mlcc/CL10A226MO7JZN.do"
			(at 379.73 17.78 0)
			(effects
				(font
					(size 1.27 1.27)
					(thickness 0.15)
				)
				(justify left bottom)
				(hide yes)
			)
		)
		(property "Description" "SMD Multilayer Ceramic Capacitor"
			(at 364.49 38.1 0)
			(effects
				(font
					(size 1.27 1.27)
				)
				(hide yes)
			)
		)
		(property "MPN" "CL10A226MO7JZNC"
			(at 382.27 17.78 0)
			(effects
				(font
					(size 1.27 1.27)
					(thickness 0.15)
				)
				(justify left bottom)
				(hide yes)
			)
		)
		(property "Manufacturer" "Samsung Electro-Mechanics"
			(at 384.81 17.78 0)
			(effects
				(font
					(size 1.27 1.27)
					(thickness 0.15)
				)
				(justify left bottom)
				(hide yes)
			)
		)
		(property "License" "Apache-2.0"
			(at 387.35 17.78 0)
			(effects
				(font
					(size 1.27 1.27)
					(thickness 0.15)
				)
				(justify left bottom)
				(hide yes)
			)
		)
		(property "Author" "Antmicro"
			(at 389.89 17.78 0)
			(effects
				(font
					(size 1.27 1.27)
					(thickness 0.15)
				)
				(justify left bottom)
				(hide yes)
			)
		)
		(property "Val" "22u"
			(at 366.268 36.83 90)
			(effects
				(font
					(size 1.27 1.27)
					(thickness 0.15)
				)
				(justify right)
			)
		)
		(property "Voltage" "16V"
			(at 367.03 38.0935 90)
			(effects
				(font
					(size 1.27 1.27)
				)
				(justify right)
				(hide yes)
			)
		)
		(property "Dielectric" ""
			(at 394.97 17.78 0)
			(effects
				(font
					(size 1.27 1.27)
				)
				(justify left bottom)
				(hide yes)
			)
		)
		(pin "2"
		)
		(pin "1"
		)
		(instances
			(project "thunderbolt-to-10gbe-adapter"
				(path ""
					(reference "C144")
					(unit 1)
				)
			)
		)
	)
	(symbol
		(lib_id "antmicropower:GND")
		(at 332.74 157.48 0)
		(unit 1)
		(exclude_from_sim no)
		(in_bom yes)
		(on_board yes)
		(dnp no)
		(property "Reference" "#PWR0186"
			(at 341.63 160.02 0)
			(effects
				(font
					(size 1.27 1.27)
					(thickness 0.15)
				)
				(justify left bottom)
				(hide yes)
			)
		)
		(property "Value" "GND"
			(at 332.74 161.29 0)
			(effects
				(font
					(size 1.27 1.27)
					(thickness 0.15)
				)
			)
		)
		(property "Footprint" ""
			(at 341.63 165.1 0)
			(effects
				(font
					(size 1.27 1.27)
					(thickness 0.15)
				)
				(justify left bottom)
				(hide yes)
			)
		)
		(property "Datasheet" ""
			(at 341.63 170.18 0)
			(effects
				(font
					(size 1.27 1.27)
					(thickness 0.15)
				)
				(justify left bottom)
				(hide yes)
			)
		)
		(property "Description" ""
			(at 332.74 157.48 0)
			(effects
				(font
					(size 1.27 1.27)
				)
				(hide yes)
			)
		)
		(property "Author" "Antmicro"
			(at 341.63 165.1 0)
			(effects
				(font
					(size 1.27 1.27)
					(thickness 0.15)
				)
				(justify left bottom)
				(hide yes)
			)
		)
		(property "License" "Apache-2.0"
			(at 341.63 167.64 0)
			(effects
				(font
					(size 1.27 1.27)
					(thickness 0.15)
				)
				(justify left bottom)
				(hide yes)
			)
		)
		(pin "1"
		)
		(instances
			(project "thunderbolt-to-10gbe-adapter"
				(path ""
					(reference "#PWR0186")
					(unit 1)
				)
			)
		)
	)
	(symbol
		(lib_id "antmicropower:GND")
		(at 354.33 195.58 0)
		(unit 1)
		(exclude_from_sim no)
		(in_bom yes)
		(on_board yes)
		(dnp no)
		(property "Reference" "#PWR0197"
			(at 363.22 198.12 0)
			(effects
				(font
					(size 1.27 1.27)
					(thickness 0.15)
				)
				(justify left bottom)
				(hide yes)
			)
		)
		(property "Value" "GND"
			(at 354.33 199.39 0)
			(effects
				(font
					(size 1.27 1.27)
					(thickness 0.15)
				)
			)
		)
		(property "Footprint" ""
			(at 363.22 203.2 0)
			(effects
				(font
					(size 1.27 1.27)
					(thickness 0.15)
				)
				(justify left bottom)
				(hide yes)
			)
		)
		(property "Datasheet" ""
			(at 363.22 208.28 0)
			(effects
				(font
					(size 1.27 1.27)
					(thickness 0.15)
				)
				(justify left bottom)
				(hide yes)
			)
		)
		(property "Description" ""
			(at 354.33 195.58 0)
			(effects
				(font
					(size 1.27 1.27)
				)
				(hide yes)
			)
		)
		(property "Author" "Antmicro"
			(at 363.22 203.2 0)
			(effects
				(font
					(size 1.27 1.27)
					(thickness 0.15)
				)
				(justify left bottom)
				(hide yes)
			)
		)
		(property "License" "Apache-2.0"
			(at 363.22 205.74 0)
			(effects
				(font
					(size 1.27 1.27)
					(thickness 0.15)
				)
				(justify left bottom)
				(hide yes)
			)
		)
		(pin "1"
		)
		(instances
			(project "thunderbolt-to-10gbe-adapter"
				(path ""
					(reference "#PWR0197")
					(unit 1)
				)
			)
		)
	)
	(symbol
		(lib_id "antmicropower:GND")
		(at 354.33 119.38 0)
		(unit 1)
		(exclude_from_sim no)
		(in_bom yes)
		(on_board yes)
		(dnp no)
		(property "Reference" "#PWR0195"
			(at 363.22 121.92 0)
			(effects
				(font
					(size 1.27 1.27)
					(thickness 0.15)
				)
				(justify left bottom)
				(hide yes)
			)
		)
		(property "Value" "GND"
			(at 354.33 123.19 0)
			(effects
				(font
					(size 1.27 1.27)
					(thickness 0.15)
				)
			)
		)
		(property "Footprint" ""
			(at 363.22 127 0)
			(effects
				(font
					(size 1.27 1.27)
					(thickness 0.15)
				)
				(justify left bottom)
				(hide yes)
			)
		)
		(property "Datasheet" ""
			(at 363.22 132.08 0)
			(effects
				(font
					(size 1.27 1.27)
					(thickness 0.15)
				)
				(justify left bottom)
				(hide yes)
			)
		)
		(property "Description" ""
			(at 354.33 119.38 0)
			(effects
				(font
					(size 1.27 1.27)
				)
				(hide yes)
			)
		)
		(property "Author" "Antmicro"
			(at 363.22 127 0)
			(effects
				(font
					(size 1.27 1.27)
					(thickness 0.15)
				)
				(justify left bottom)
				(hide yes)
			)
		)
		(property "License" "Apache-2.0"
			(at 363.22 129.54 0)
			(effects
				(font
					(size 1.27 1.27)
					(thickness 0.15)
				)
				(justify left bottom)
				(hide yes)
			)
		)
		(pin "1"
		)
		(instances
			(project "thunderbolt-to-10gbe-adapter"
				(path ""
					(reference "#PWR0195")
					(unit 1)
				)
			)
		)
	)
	(symbol
		(lib_id "antmicropower:GND")
		(at 364.49 81.28 0)
		(unit 1)
		(exclude_from_sim no)
		(in_bom yes)
		(on_board yes)
		(dnp no)
		(property "Reference" "#PWR0199"
			(at 373.38 83.82 0)
			(effects
				(font
					(size 1.27 1.27)
					(thickness 0.15)
				)
				(justify left bottom)
				(hide yes)
			)
		)
		(property "Value" "GND"
			(at 364.49 85.09 0)
			(effects
				(font
					(size 1.27 1.27)
					(thickness 0.15)
				)
			)
		)
		(property "Footprint" ""
			(at 373.38 88.9 0)
			(effects
				(font
					(size 1.27 1.27)
					(thickness 0.15)
				)
				(justify left bottom)
				(hide yes)
			)
		)
		(property "Datasheet" ""
			(at 373.38 93.98 0)
			(effects
				(font
					(size 1.27 1.27)
					(thickness 0.15)
				)
				(justify left bottom)
				(hide yes)
			)
		)
		(property "Description" ""
			(at 364.49 81.28 0)
			(effects
				(font
					(size 1.27 1.27)
				)
				(hide yes)
			)
		)
		(property "Author" "Antmicro"
			(at 373.38 88.9 0)
			(effects
				(font
					(size 1.27 1.27)
					(thickness 0.15)
				)
				(justify left bottom)
				(hide yes)
			)
		)
		(property "License" "Apache-2.0"
			(at 373.38 91.44 0)
			(effects
				(font
					(size 1.27 1.27)
					(thickness 0.15)
				)
				(justify left bottom)
				(hide yes)
			)
		)
		(pin "1"
		)
		(instances
			(project "thunderbolt-to-10gbe-adapter"
				(path ""
					(reference "#PWR0199")
					(unit 1)
				)
			)
		)
	)
	(symbol
		(lib_id "antmicropower:VDD")
		(at 387.35 238.76 90)
		(unit 1)
		(exclude_from_sim no)
		(in_bom yes)
		(on_board yes)
		(dnp no)
		(fields_autoplaced yes)
		(property "Reference" "#PWR0212"
			(at 391.16 238.76 0)
			(effects
				(font
					(size 1.27 1.27)
				)
				(hide yes)
			)
		)
		(property "Value" "DVDD"
			(at 383.54 238.7599 90)
			(effects
				(font
					(size 1.27 1.27)
				)
				(justify left)
			)
		)
		(property "Footprint" ""
			(at 387.35 238.76 0)
			(effects
				(font
					(size 1.27 1.27)
				)
				(hide yes)
			)
		)
		(property "Datasheet" ""
			(at 387.35 238.76 0)
			(effects
				(font
					(size 1.27 1.27)
				)
				(hide yes)
			)
		)
		(property "Description" ""
			(at 387.35 238.76 0)
			(effects
				(font
					(size 1.27 1.27)
				)
				(hide yes)
			)
		)
		(pin "1"
		)
		(instances
			(project "thunderbolt-to-10gbe-adapter"
				(path ""
					(reference "#PWR0212")
					(unit 1)
				)
			)
		)
	)
	(symbol
		(lib_id "antmicropower:+5V")
		(at 217.17 137.16 0)
		(unit 1)
		(exclude_from_sim no)
		(in_bom yes)
		(on_board yes)
		(dnp no)
		(property "Reference" "#PWR0155"
			(at 232.41 139.7 0)
			(effects
				(font
					(size 1.27 1.27)
					(thickness 0.15)
				)
				(justify left bottom)
				(hide yes)
			)
		)
		(property "Value" "+5V"
			(at 217.17 133.35 0)
			(effects
				(font
					(size 1.27 1.27)
					(thickness 0.15)
				)
			)
		)
		(property "Footprint" ""
			(at 232.41 144.78 0)
			(effects
				(font
					(size 1.27 1.27)
					(thickness 0.15)
				)
				(justify left bottom)
				(hide yes)
			)
		)
		(property "Datasheet" ""
			(at 232.41 147.32 0)
			(effects
				(font
					(size 1.27 1.27)
					(thickness 0.15)
				)
				(justify left bottom)
				(hide yes)
			)
		)
		(property "Description" ""
			(at 232.41 149.86 0)
			(effects
				(font
					(size 1.27 1.27)
				)
				(justify left bottom)
				(hide yes)
			)
		)
		(property "Author" "Antmicro"
			(at 232.41 144.78 0)
			(effects
				(font
					(size 1.27 1.27)
					(thickness 0.15)
				)
				(justify left bottom)
				(hide yes)
			)
		)
		(property "License" "Apache-2.0"
			(at 232.41 147.32 0)
			(effects
				(font
					(size 1.27 1.27)
					(thickness 0.15)
				)
				(justify left bottom)
				(hide yes)
			)
		)
		(pin "1"
		)
		(instances
			(project "thunderbolt-to-10gbe-adapter"
				(path ""
					(reference "#PWR0155")
					(unit 1)
				)
			)
		)
	)
	(symbol
		(lib_id "antmicroTransistorsBipolarSingle:DTC014T_SOT-416")
		(at 220.98 238.76 0)
		(unit 1)
		(exclude_from_sim no)
		(in_bom yes)
		(on_board yes)
		(dnp no)
		(property "Reference" "Q3"
			(at 230.378 240.03 0)
			(effects
				(font
					(size 1.27 1.27)
					(thickness 0.15)
				)
				(justify left)
			)
		)
		(property "Value" "DTC014T_SOT-416"
			(at 246.38 246.38 0)
			(effects
				(font
					(size 1.27 1.27)
					(thickness 0.15)
				)
				(justify left bottom)
				(hide yes)
			)
		)
		(property "Footprint" "antmicro-footprints:SOT-416"
			(at 246.38 248.92 0)
			(effects
				(font
					(size 1.27 1.27)
					(thickness 0.15)
				)
				(justify left bottom)
				(hide yes)
			)
		)
		(property "Datasheet" "https://www.rohm.com/datasheet?p=DTC014TEB&dist=Mouser&media=referral&source=mouser.com&campaign=Mouser"
			(at 246.38 251.46 0)
			(effects
				(font
					(size 1.27 1.27)
					(thickness 0.15)
				)
				(justify left bottom)
				(hide yes)
			)
		)
		(property "Description" "Bipolar (BJT) Single Transistor with built-in base resistor, NPN, 50V, 100mA, 150mW, SOT-416FL, Surface Mount"
			(at 246.38 264.16 0)
			(effects
				(font
					(size 1.27 1.27)
				)
				(justify left bottom)
				(hide yes)
			)
		)
		(property "Manufacturer" "ROHM Semiconductor"
			(at 246.38 254 0)
			(effects
				(font
					(size 1.27 1.27)
					(thickness 0.15)
				)
				(justify left bottom)
				(hide yes)
			)
		)
		(property "MPN" "DTC014TEBTL"
			(at 230.378 242.57 0)
			(effects
				(font
					(size 1.27 1.27)
					(thickness 0.15)
				)
				(justify left)
			)
		)
		(property "Author" "Antmicro"
			(at 246.38 259.08 0)
			(effects
				(font
					(size 1.27 1.27)
					(thickness 0.15)
				)
				(justify left bottom)
				(hide yes)
			)
		)
		(property "License" "Apache-2.0"
			(at 246.38 261.62 0)
			(effects
				(font
					(size 1.27 1.27)
					(thickness 0.15)
				)
				(justify left bottom)
				(hide yes)
			)
		)
		(pin "1"
		)
		(pin "2"
		)
		(pin "3"
		)
		(instances
			(project "thunderbolt-to-10gbe-adapter"
				(path ""
					(reference "Q3")
					(unit 1)
				)
			)
		)
	)
	(symbol
		(lib_id "antmicroCapacitors0402:C_100n_0402")
		(at 374.65 114.3 90)
		(unit 1)
		(exclude_from_sim no)
		(in_bom yes)
		(on_board yes)
		(dnp no)
		(property "Reference" "C151"
			(at 376.428 110.49 90)
			(effects
				(font
					(size 1.27 1.27)
					(thickness 0.15)
				)
				(justify right)
			)
		)
		(property "Value" "C_100n_0402"
			(at 384.81 93.98 0)
			(effects
				(font
					(size 1.27 1.27)
					(thickness 0.15)
				)
				(justify left bottom)
				(hide yes)
			)
		)
		(property "Footprint" "antmicro-footprints:C_0402_1005Metric"
			(at 387.35 93.98 0)
			(effects
				(font
					(size 1.27 1.27)
					(thickness 0.15)
				)
				(justify left bottom)
				(hide yes)
			)
		)
		(property "Datasheet" "https://www.murata.com/products/productdetail?partno=GRM155R61H104KE14%23"
			(at 389.89 93.98 0)
			(effects
				(font
					(size 1.27 1.27)
					(thickness 0.15)
				)
				(justify left bottom)
				(hide yes)
			)
		)
		(property "Description" "SMD Multilayer Ceramic Capacitor, 0.1 µF, 50 V, 0402 [1005 Metric], ± 10%, X5R, GRM Series"
			(at 407.67 93.98 0)
			(effects
				(font
					(size 1.27 1.27)
				)
				(justify left bottom)
				(hide yes)
			)
		)
		(property "MPN" "GRM155R61H104KE14D"
			(at 392.43 93.98 0)
			(effects
				(font
					(size 1.27 1.27)
					(thickness 0.15)
				)
				(justify left bottom)
				(hide yes)
			)
		)
		(property "Manufacturer" "Murata"
			(at 394.97 93.98 0)
			(effects
				(font
					(size 1.27 1.27)
					(thickness 0.15)
				)
				(justify left bottom)
				(hide yes)
			)
		)
		(property "License" "Apache-2.0"
			(at 397.51 93.98 0)
			(effects
				(font
					(size 1.27 1.27)
					(thickness 0.15)
				)
				(justify left bottom)
				(hide yes)
			)
		)
		(property "Author" "Antmicro"
			(at 400.05 93.98 0)
			(effects
				(font
					(size 1.27 1.27)
					(thickness 0.15)
				)
				(justify left bottom)
				(hide yes)
			)
		)
		(property "Val" "100n"
			(at 376.428 113.03 90)
			(effects
				(font
					(size 1.27 1.27)
					(thickness 0.15)
				)
				(justify right)
			)
		)
		(property "Voltage" "50V"
			(at 402.59 93.98 0)
			(effects
				(font
					(size 1.27 1.27)
				)
				(justify left bottom)
				(hide yes)
			)
		)
		(property "Dielectric" "X5R"
			(at 405.13 93.98 0)
			(effects
				(font
					(size 1.27 1.27)
				)
				(justify left bottom)
				(hide yes)
			)
		)
		(pin "1"
		)
		(pin "2"
		)
		(instances
			(project "thunderbolt-to-10gbe-adapter"
				(path ""
					(reference "C151")
					(unit 1)
				)
			)
		)
	)
	(symbol
		(lib_id "antmicropower:GND")
		(at 344.17 119.38 0)
		(unit 1)
		(exclude_from_sim no)
		(in_bom yes)
		(on_board yes)
		(dnp no)
		(property "Reference" "#PWR0190"
			(at 353.06 121.92 0)
			(effects
				(font
					(size 1.27 1.27)
					(thickness 0.15)
				)
				(justify left bottom)
				(hide yes)
			)
		)
		(property "Value" "GND"
			(at 344.17 123.19 0)
			(effects
				(font
					(size 1.27 1.27)
					(thickness 0.15)
				)
			)
		)
		(property "Footprint" ""
			(at 353.06 127 0)
			(effects
				(font
					(size 1.27 1.27)
					(thickness 0.15)
				)
				(justify left bottom)
				(hide yes)
			)
		)
		(property "Datasheet" ""
			(at 353.06 132.08 0)
			(effects
				(font
					(size 1.27 1.27)
					(thickness 0.15)
				)
				(justify left bottom)
				(hide yes)
			)
		)
		(property "Description" ""
			(at 344.17 119.38 0)
			(effects
				(font
					(size 1.27 1.27)
				)
				(hide yes)
			)
		)
		(property "Author" "Antmicro"
			(at 353.06 127 0)
			(effects
				(font
					(size 1.27 1.27)
					(thickness 0.15)
				)
				(justify left bottom)
				(hide yes)
			)
		)
		(property "License" "Apache-2.0"
			(at 353.06 129.54 0)
			(effects
				(font
					(size 1.27 1.27)
					(thickness 0.15)
				)
				(justify left bottom)
				(hide yes)
			)
		)
		(pin "1"
		)
		(instances
			(project "thunderbolt-to-10gbe-adapter"
				(path ""
					(reference "#PWR0190")
					(unit 1)
				)
			)
		)
	)
	(symbol
		(lib_id "antmicropower:VDD")
		(at 400.05 175.26 0)
		(unit 1)
		(exclude_from_sim no)
		(in_bom yes)
		(on_board yes)
		(dnp no)
		(property "Reference" "#PWR0217"
			(at 400.05 179.07 0)
			(effects
				(font
					(size 1.27 1.27)
				)
				(hide yes)
			)
		)
		(property "Value" "DVDD"
			(at 400.05 171.45 0)
			(effects
				(font
					(size 1.27 1.27)
				)
			)
		)
		(property "Footprint" ""
			(at 400.05 175.26 0)
			(effects
				(font
					(size 1.27 1.27)
				)
				(hide yes)
			)
		)
		(property "Datasheet" ""
			(at 400.05 175.26 0)
			(effects
				(font
					(size 1.27 1.27)
				)
				(hide yes)
			)
		)
		(property "Description" ""
			(at 400.05 175.26 0)
			(effects
				(font
					(size 1.27 1.27)
				)
				(hide yes)
			)
		)
		(pin "1"
		)
		(instances
			(project "thunderbolt-to-10gbe-adapter"
				(path ""
					(reference "#PWR0217")
					(unit 1)
				)
			)
		)
	)
	(symbol
		(lib_id "antmicropower:GND")
		(at 304.8 246.38 0)
		(unit 1)
		(exclude_from_sim no)
		(in_bom yes)
		(on_board yes)
		(dnp no)
		(property "Reference" "#PWR0182"
			(at 313.69 248.92 0)
			(effects
				(font
					(size 1.27 1.27)
					(thickness 0.15)
				)
				(justify left bottom)
				(hide yes)
			)
		)
		(property "Value" "GND"
			(at 304.8 250.19 0)
			(effects
				(font
					(size 1.27 1.27)
					(thickness 0.15)
				)
			)
		)
		(property "Footprint" ""
			(at 313.69 254 0)
			(effects
				(font
					(size 1.27 1.27)
					(thickness 0.15)
				)
				(justify left bottom)
				(hide yes)
			)
		)
		(property "Datasheet" ""
			(at 313.69 259.08 0)
			(effects
				(font
					(size 1.27 1.27)
					(thickness 0.15)
				)
				(justify left bottom)
				(hide yes)
			)
		)
		(property "Description" ""
			(at 304.8 246.38 0)
			(effects
				(font
					(size 1.27 1.27)
				)
				(hide yes)
			)
		)
		(property "Author" "Antmicro"
			(at 313.69 254 0)
			(effects
				(font
					(size 1.27 1.27)
					(thickness 0.15)
				)
				(justify left bottom)
				(hide yes)
			)
		)
		(property "License" "Apache-2.0"
			(at 313.69 256.54 0)
			(effects
				(font
					(size 1.27 1.27)
					(thickness 0.15)
				)
				(justify left bottom)
				(hide yes)
			)
		)
		(pin "1"
		)
		(instances
			(project "thunderbolt-to-10gbe-adapter"
				(path ""
					(reference "#PWR0182")
					(unit 1)
				)
			)
		)
	)
)
